(kicad_sch
	(version 20231120)
	(generator "eeschema")
	(generator_version "8.0")
	(paper "A3" portrait)
	(title_block
		(title "Thunderbolt GPU Adapter")
		(date "2024-07-09")
		(rev "1.3.0")
		(company "Antmicro Ltd")
		(comment 1 "www.antmicro.com")
	)
	(junction
		(at 199.39 213.36)
		(diameter 0)
		(color 0 0 0 0)
	)
	(junction
		(at 176.53 175.26)
		(diameter 0)
		(color 0 0 0 0)
	)
	(junction
		(at 116.84 175.26)
		(diameter 0)
		(color 0 0 0 0)
	)
	(junction
		(at 246.38 214.63)
		(diameter 0)
		(color 0 0 0 0)
	)
	(junction
		(at 199.39 125.73)
		(diameter 0)
		(color 0 0 0 0)
	)
	(junction
		(at 186.69 193.04)
		(diameter 0)
		(color 0 0 0 0)
	)
	(junction
		(at 199.39 193.04)
		(diameter 0)
		(color 0 0 0 0)
	)
	(junction
		(at 111.76 175.26)
		(diameter 0)
		(color 0 0 0 0)
	)
	(junction
		(at 116.84 278.13)
		(diameter 0)
		(color 0 0 0 0)
	)
	(junction
		(at 116.84 157.48)
		(diameter 0)
		(color 0 0 0 0)
	)
	(junction
		(at 176.53 213.36)
		(diameter 0)
		(color 0 0 0 0)
	)
	(junction
		(at 121.92 139.7)
		(diameter 0)
		(color 0 0 0 0)
	)
	(junction
		(at 105.41 157.48)
		(diameter 0)
		(color 0 0 0 0)
	)
	(junction
		(at 193.04 125.73)
		(diameter 0)
		(color 0 0 0 0)
	)
	(junction
		(at 231.14 125.73)
		(diameter 0)
		(color 0 0 0 0)
	)
	(junction
		(at 116.84 139.7)
		(diameter 0)
		(color 0 0 0 0)
	)
	(junction
		(at 205.74 175.26)
		(diameter 0)
		(color 0 0 0 0)
	)
	(junction
		(at 186.69 142.24)
		(diameter 0)
		(color 0 0 0 0)
	)
	(junction
		(at 100.33 157.48)
		(diameter 0)
		(color 0 0 0 0)
	)
	(junction
		(at 105.41 139.7)
		(diameter 0)
		(color 0 0 0 0)
	)
	(junction
		(at 121.92 142.24)
		(diameter 0)
		(color 0 0 0 0)
	)
	(junction
		(at 237.49 125.73)
		(diameter 0)
		(color 0 0 0 0)
	)
	(junction
		(at 229.87 208.28)
		(diameter 0)
		(color 0 0 0 0)
	)
	(junction
		(at 207.01 281.94)
		(diameter 0)
		(color 0 0 0 0)
	)
	(junction
		(at 180.34 142.24)
		(diameter 0)
		(color 0 0 0 0)
	)
	(junction
		(at 186.69 175.26)
		(diameter 0)
		(color 0 0 0 0)
	)
	(junction
		(at 193.04 213.36)
		(diameter 0)
		(color 0 0 0 0)
	)
	(junction
		(at 111.76 193.04)
		(diameter 0)
		(color 0 0 0 0)
	)
	(junction
		(at 199.39 157.48)
		(diameter 0)
		(color 0 0 0 0)
	)
	(junction
		(at 116.84 193.04)
		(diameter 0)
		(color 0 0 0 0)
	)
	(junction
		(at 212.09 125.73)
		(diameter 0)
		(color 0 0 0 0)
	)
	(junction
		(at 121.92 160.02)
		(diameter 0)
		(color 0 0 0 0)
	)
	(junction
		(at 193.04 175.26)
		(diameter 0)
		(color 0 0 0 0)
	)
	(junction
		(at 111.76 157.48)
		(diameter 0)
		(color 0 0 0 0)
	)
	(junction
		(at 93.98 139.7)
		(diameter 0)
		(color 0 0 0 0)
	)
	(junction
		(at 212.09 157.48)
		(diameter 0)
		(color 0 0 0 0)
	)
	(junction
		(at 219.71 193.04)
		(diameter 0)
		(color 0 0 0 0)
	)
	(junction
		(at 199.39 175.26)
		(diameter 0)
		(color 0 0 0 0)
	)
	(junction
		(at 121.92 157.48)
		(diameter 0)
		(color 0 0 0 0)
	)
	(junction
		(at 180.34 175.26)
		(diameter 0)
		(color 0 0 0 0)
	)
	(junction
		(at 186.69 125.73)
		(diameter 0)
		(color 0 0 0 0)
	)
	(junction
		(at 193.04 157.48)
		(diameter 0)
		(color 0 0 0 0)
	)
	(junction
		(at 205.74 125.73)
		(diameter 0)
		(color 0 0 0 0)
	)
	(junction
		(at 100.33 193.04)
		(diameter 0)
		(color 0 0 0 0)
	)
	(junction
		(at 205.74 193.04)
		(diameter 0)
		(color 0 0 0 0)
	)
	(junction
		(at 116.84 284.48)
		(diameter 0)
		(color 0 0 0 0)
	)
	(junction
		(at 186.69 157.48)
		(diameter 0)
		(color 0 0 0 0)
	)
	(junction
		(at 105.41 193.04)
		(diameter 0)
		(color 0 0 0 0)
	)
	(junction
		(at 186.69 213.36)
		(diameter 0)
		(color 0 0 0 0)
	)
	(junction
		(at 180.34 125.73)
		(diameter 0)
		(color 0 0 0 0)
	)
	(junction
		(at 100.33 139.7)
		(diameter 0)
		(color 0 0 0 0)
	)
	(junction
		(at 217.17 215.9)
		(diameter 0)
		(color 0 0 0 0)
	)
	(junction
		(at 176.53 142.24)
		(diameter 0)
		(color 0 0 0 0)
	)
	(junction
		(at 193.04 193.04)
		(diameter 0)
		(color 0 0 0 0)
	)
	(junction
		(at 111.76 139.7)
		(diameter 0)
		(color 0 0 0 0)
	)
	(junction
		(at 176.53 177.8)
		(diameter 0)
		(color 0 0 0 0)
	)
	(junction
		(at 214.63 193.04)
		(diameter 0)
		(color 0 0 0 0)
	)
	(junction
		(at 218.44 125.73)
		(diameter 0)
		(color 0 0 0 0)
	)
	(junction
		(at 224.79 125.73)
		(diameter 0)
		(color 0 0 0 0)
	)
	(wire
		(pts
			(xy 179.07 195.58) (xy 179.07 198.12)
		)
		(stroke
			(width 0)
			(type default)
		)
	)
	(wire
		(pts
			(xy 212.09 157.48) (xy 217.17 157.48)
		)
		(stroke
			(width 0)
			(type default)
		)
	)
	(wire
		(pts
			(xy 218.44 133.35) (xy 218.44 134.62)
		)
		(stroke
			(width 0)
			(type default)
		)
	)
	(wire
		(pts
			(xy 199.39 213.36) (xy 205.74 213.36)
		)
		(stroke
			(width 0)
			(type default)
		)
	)
	(wire
		(pts
			(xy 105.41 166.37) (xy 105.41 168.91)
		)
		(stroke
			(width 0)
			(type default)
		)
	)
	(wire
		(pts
			(xy 186.69 157.48) (xy 193.04 157.48)
		)
		(stroke
			(width 0)
			(type default)
		)
	)
	(wire
		(pts
			(xy 111.76 157.48) (xy 105.41 157.48)
		)
		(stroke
			(width 0)
			(type default)
		)
	)
	(wire
		(pts
			(xy 88.9 191.77) (xy 88.9 193.04)
		)
		(stroke
			(width 0)
			(type default)
		)
	)
	(wire
		(pts
			(xy 217.17 222.25) (xy 217.17 223.52)
		)
		(stroke
			(width 0)
			(type default)
		)
	)
	(wire
		(pts
			(xy 199.39 125.73) (xy 205.74 125.73)
		)
		(stroke
			(width 0)
			(type default)
		)
	)
	(wire
		(pts
			(xy 180.34 175.26) (xy 176.53 175.26)
		)
		(stroke
			(width 0)
			(type default)
		)
	)
	(wire
		(pts
			(xy 180.34 142.24) (xy 180.34 144.78)
		)
		(stroke
			(width 0)
			(type default)
		)
	)
	(wire
		(pts
			(xy 205.74 213.36) (xy 205.74 217.17)
		)
		(stroke
			(width 0)
			(type default)
		)
	)
	(wire
		(pts
			(xy 205.74 125.73) (xy 212.09 125.73)
		)
		(stroke
			(width 0)
			(type default)
		)
	)
	(wire
		(pts
			(xy 205.74 193.04) (xy 205.74 196.85)
		)
		(stroke
			(width 0)
			(type default)
		)
	)
	(wire
		(pts
			(xy 88.9 139.7) (xy 88.9 143.51)
		)
		(stroke
			(width 0)
			(type default)
		)
	)
	(wire
		(pts
			(xy 116.84 284.48) (xy 116.84 287.02)
		)
		(stroke
			(width 0)
			(type default)
		)
	)
	(wire
		(pts
			(xy 199.39 175.26) (xy 199.39 177.8)
		)
		(stroke
			(width 0)
			(type default)
		)
	)
	(wire
		(pts
			(xy 193.04 157.48) (xy 193.04 160.02)
		)
		(stroke
			(width 0)
			(type default)
		)
	)
	(wire
		(pts
			(xy 212.09 157.48) (xy 212.09 160.02)
		)
		(stroke
			(width 0)
			(type default)
		)
	)
	(wire
		(pts
			(xy 111.76 157.48) (xy 111.76 161.29)
		)
		(stroke
			(width 0)
			(type default)
		)
	)
	(wire
		(pts
			(xy 121.92 157.48) (xy 121.92 160.02)
		)
		(stroke
			(width 0)
			(type default)
		)
	)
	(wire
		(pts
			(xy 116.84 193.04) (xy 116.84 196.85)
		)
		(stroke
			(width 0)
			(type default)
		)
	)
	(wire
		(pts
			(xy 193.04 165.1) (xy 193.04 167.64)
		)
		(stroke
			(width 0)
			(type default)
		)
	)
	(wire
		(pts
			(xy 176.53 210.82) (xy 176.53 213.36)
		)
		(stroke
			(width 0)
			(type default)
		)
	)
	(wire
		(pts
			(xy 121.92 210.82) (xy 111.76 210.82)
		)
		(stroke
			(width 0)
			(type default)
		)
	)
	(wire
		(pts
			(xy 229.87 193.04) (xy 229.87 198.12)
		)
		(stroke
			(width 0)
			(type default)
		)
	)
	(wire
		(pts
			(xy 111.76 201.93) (xy 111.76 203.2)
		)
		(stroke
			(width 0)
			(type default)
		)
	)
	(wire
		(pts
			(xy 176.53 125.73) (xy 180.34 125.73)
		)
		(stroke
			(width 0)
			(type default)
		)
	)
	(wire
		(pts
			(xy 217.17 287.02) (xy 217.17 292.1)
		)
		(stroke
			(width 0)
			(type default)
		)
	)
	(wire
		(pts
			(xy 116.84 278.13) (xy 123.19 278.13)
		)
		(stroke
			(width 0)
			(type default)
		)
	)
	(wire
		(pts
			(xy 186.69 157.48) (xy 186.69 160.02)
		)
		(stroke
			(width 0)
			(type default)
		)
	)
	(wire
		(pts
			(xy 111.76 148.59) (xy 111.76 151.13)
		)
		(stroke
			(width 0)
			(type default)
		)
	)
	(wire
		(pts
			(xy 199.39 222.25) (xy 199.39 224.79)
		)
		(stroke
			(width 0)
			(type default)
		)
	)
	(wire
		(pts
			(xy 193.04 125.73) (xy 193.04 128.27)
		)
		(stroke
			(width 0)
			(type default)
		)
	)
	(wire
		(pts
			(xy 111.76 210.82) (xy 111.76 217.17)
		)
		(stroke
			(width 0)
			(type default)
		)
	)
	(wire
		(pts
			(xy 219.71 191.77) (xy 219.71 193.04)
		)
		(stroke
			(width 0)
			(type default)
		)
	)
	(wire
		(pts
			(xy 229.87 203.2) (xy 229.87 208.28)
		)
		(stroke
			(width 0)
			(type default)
		)
	)
	(wire
		(pts
			(xy 105.41 148.59) (xy 105.41 151.13)
		)
		(stroke
			(width 0)
			(type default)
		)
	)
	(wire
		(pts
			(xy 205.74 193.04) (xy 214.63 193.04)
		)
		(stroke
			(width 0)
			(type default)
		)
	)
	(wire
		(pts
			(xy 186.69 193.04) (xy 186.69 196.85)
		)
		(stroke
			(width 0)
			(type default)
		)
	)
	(wire
		(pts
			(xy 231.14 133.35) (xy 231.14 134.62)
		)
		(stroke
			(width 0)
			(type default)
		)
	)
	(wire
		(pts
			(xy 100.33 157.48) (xy 100.33 161.29)
		)
		(stroke
			(width 0)
			(type default)
		)
	)
	(wire
		(pts
			(xy 186.69 201.93) (xy 186.69 203.2)
		)
		(stroke
			(width 0)
			(type default)
		)
	)
	(wire
		(pts
			(xy 111.76 184.15) (xy 111.76 186.69)
		)
		(stroke
			(width 0)
			(type default)
		)
	)
	(wire
		(pts
			(xy 241.3 208.28) (xy 246.38 208.28)
		)
		(stroke
			(width 0)
			(type default)
		)
	)
	(wire
		(pts
			(xy 193.04 175.26) (xy 199.39 175.26)
		)
		(stroke
			(width 0)
			(type default)
		)
	)
	(wire
		(pts
			(xy 217.17 214.63) (xy 217.17 215.9)
		)
		(stroke
			(width 0)
			(type default)
		)
	)
	(wire
		(pts
			(xy 116.84 284.48) (xy 123.19 284.48)
		)
		(stroke
			(width 0)
			(type default)
		)
	)
	(wire
		(pts
			(xy 205.74 175.26) (xy 214.63 175.26)
		)
		(stroke
			(width 0)
			(type default)
		)
	)
	(wire
		(pts
			(xy 224.79 125.73) (xy 231.14 125.73)
		)
		(stroke
			(width 0)
			(type default)
		)
	)
	(wire
		(pts
			(xy 180.34 133.35) (xy 180.34 134.62)
		)
		(stroke
			(width 0)
			(type default)
		)
	)
	(wire
		(pts
			(xy 224.79 125.73) (xy 224.79 128.27)
		)
		(stroke
			(width 0)
			(type default)
		)
	)
	(wire
		(pts
			(xy 121.92 213.36) (xy 116.84 213.36)
		)
		(stroke
			(width 0)
			(type default)
		)
	)
	(wire
		(pts
			(xy 121.92 160.02) (xy 121.92 162.56)
		)
		(stroke
			(width 0)
			(type default)
		)
	)
	(wire
		(pts
			(xy 205.74 201.93) (xy 205.74 203.2)
		)
		(stroke
			(width 0)
			(type default)
		)
	)
	(wire
		(pts
			(xy 111.76 193.04) (xy 111.76 196.85)
		)
		(stroke
			(width 0)
			(type default)
		)
	)
	(wire
		(pts
			(xy 111.76 166.37) (xy 111.76 168.91)
		)
		(stroke
			(width 0)
			(type default)
		)
	)
	(wire
		(pts
			(xy 246.38 214.63) (xy 243.84 214.63)
		)
		(stroke
			(width 0)
			(type default)
		)
	)
	(wire
		(pts
			(xy 199.39 193.04) (xy 199.39 196.85)
		)
		(stroke
			(width 0)
			(type default)
		)
	)
	(wire
		(pts
			(xy 111.76 139.7) (xy 111.76 143.51)
		)
		(stroke
			(width 0)
			(type default)
		)
	)
	(wire
		(pts
			(xy 237.49 125.73) (xy 241.3 125.73)
		)
		(stroke
			(width 0)
			(type default)
		)
	)
	(wire
		(pts
			(xy 199.39 193.04) (xy 205.74 193.04)
		)
		(stroke
			(width 0)
			(type default)
		)
	)
	(wire
		(pts
			(xy 88.9 175.26) (xy 111.76 175.26)
		)
		(stroke
			(width 0)
			(type default)
		)
	)
	(wire
		(pts
			(xy 180.34 149.86) (xy 180.34 152.4)
		)
		(stroke
			(width 0)
			(type default)
		)
	)
	(wire
		(pts
			(xy 193.04 182.88) (xy 193.04 184.15)
		)
		(stroke
			(width 0)
			(type default)
		)
	)
	(wire
		(pts
			(xy 100.33 201.93) (xy 100.33 203.2)
		)
		(stroke
			(width 0)
			(type default)
		)
	)
	(wire
		(pts
			(xy 199.39 201.93) (xy 199.39 203.2)
		)
		(stroke
			(width 0)
			(type default)
		)
	)
	(wire
		(pts
			(xy 207.01 281.94) (xy 210.82 281.94)
		)
		(stroke
			(width 0)
			(type default)
		)
	)
	(wire
		(pts
			(xy 180.34 142.24) (xy 186.69 142.24)
		)
		(stroke
			(width 0)
			(type default)
		)
	)
	(wire
		(pts
			(xy 193.04 193.04) (xy 199.39 193.04)
		)
		(stroke
			(width 0)
			(type default)
		)
	)
	(wire
		(pts
			(xy 116.84 157.48) (xy 111.76 157.48)
		)
		(stroke
			(width 0)
			(type default)
		)
	)
	(wire
		(pts
			(xy 184.15 193.04) (xy 186.69 193.04)
		)
		(stroke
			(width 0)
			(type default)
		)
	)
	(wire
		(pts
			(xy 105.41 157.48) (xy 100.33 157.48)
		)
		(stroke
			(width 0)
			(type default)
		)
	)
	(wire
		(pts
			(xy 105.41 193.04) (xy 105.41 196.85)
		)
		(stroke
			(width 0)
			(type default)
		)
	)
	(wire
		(pts
			(xy 246.38 208.28) (xy 246.38 214.63)
		)
		(stroke
			(width 0)
			(type default)
		)
	)
	(wire
		(pts
			(xy 218.44 125.73) (xy 224.79 125.73)
		)
		(stroke
			(width 0)
			(type default)
		)
	)
	(wire
		(pts
			(xy 217.17 215.9) (xy 233.68 215.9)
		)
		(stroke
			(width 0)
			(type default)
		)
	)
	(wire
		(pts
			(xy 123.19 283.21) (xy 123.19 284.48)
		)
		(stroke
			(width 0)
			(type default)
		)
	)
	(wire
		(pts
			(xy 105.41 201.93) (xy 105.41 203.2)
		)
		(stroke
			(width 0)
			(type default)
		)
	)
	(wire
		(pts
			(xy 180.34 175.26) (xy 180.34 177.8)
		)
		(stroke
			(width 0)
			(type default)
		)
	)
	(wire
		(pts
			(xy 116.84 201.93) (xy 116.84 203.2)
		)
		(stroke
			(width 0)
			(type default)
		)
	)
	(wire
		(pts
			(xy 212.09 125.73) (xy 212.09 128.27)
		)
		(stroke
			(width 0)
			(type default)
		)
	)
	(wire
		(pts
			(xy 101.6 284.48) (xy 101.6 287.02)
		)
		(stroke
			(width 0)
			(type default)
		)
	)
	(wire
		(pts
			(xy 111.76 175.26) (xy 116.84 175.26)
		)
		(stroke
			(width 0)
			(type default)
		)
	)
	(wire
		(pts
			(xy 100.33 139.7) (xy 93.98 139.7)
		)
		(stroke
			(width 0)
			(type default)
		)
	)
	(wire
		(pts
			(xy 186.69 175.26) (xy 186.69 177.8)
		)
		(stroke
			(width 0)
			(type default)
		)
	)
	(wire
		(pts
			(xy 217.17 215.9) (xy 217.17 217.17)
		)
		(stroke
			(width 0)
			(type default)
		)
	)
	(wire
		(pts
			(xy 218.44 125.73) (xy 218.44 128.27)
		)
		(stroke
			(width 0)
			(type default)
		)
	)
	(wire
		(pts
			(xy 217.17 257.81) (xy 217.17 261.62)
		)
		(stroke
			(width 0)
			(type default)
		)
	)
	(wire
		(pts
			(xy 100.33 166.37) (xy 100.33 168.91)
		)
		(stroke
			(width 0)
			(type default)
		)
	)
	(wire
		(pts
			(xy 121.92 142.24) (xy 121.92 144.78)
		)
		(stroke
			(width 0)
			(type default)
		)
	)
	(wire
		(pts
			(xy 186.69 222.25) (xy 186.69 224.79)
		)
		(stroke
			(width 0)
			(type default)
		)
	)
	(wire
		(pts
			(xy 217.17 266.7) (xy 217.17 269.24)
		)
		(stroke
			(width 0)
			(type default)
		)
	)
	(wire
		(pts
			(xy 105.41 139.7) (xy 105.41 143.51)
		)
		(stroke
			(width 0)
			(type default)
		)
	)
	(wire
		(pts
			(xy 116.84 184.15) (xy 116.84 186.69)
		)
		(stroke
			(width 0)
			(type default)
		)
	)
	(wire
		(pts
			(xy 186.69 133.35) (xy 186.69 134.62)
		)
		(stroke
			(width 0)
			(type default)
		)
	)
	(wire
		(pts
			(xy 199.39 182.88) (xy 199.39 184.15)
		)
		(stroke
			(width 0)
			(type default)
		)
	)
	(wire
		(pts
			(xy 100.33 193.04) (xy 100.33 196.85)
		)
		(stroke
			(width 0)
			(type default)
		)
	)
	(wire
		(pts
			(xy 116.84 139.7) (xy 111.76 139.7)
		)
		(stroke
			(width 0)
			(type default)
		)
	)
	(wire
		(pts
			(xy 186.69 213.36) (xy 193.04 213.36)
		)
		(stroke
			(width 0)
			(type default)
		)
	)
	(wire
		(pts
			(xy 214.63 193.04) (xy 219.71 193.04)
		)
		(stroke
			(width 0)
			(type default)
		)
	)
	(wire
		(pts
			(xy 116.84 193.04) (xy 121.92 193.04)
		)
		(stroke
			(width 0)
			(type default)
		)
	)
	(wire
		(pts
			(xy 212.09 125.73) (xy 218.44 125.73)
		)
		(stroke
			(width 0)
			(type default)
		)
	)
	(wire
		(pts
			(xy 176.53 177.8) (xy 176.53 180.34)
		)
		(stroke
			(width 0)
			(type default)
		)
	)
	(wire
		(pts
			(xy 121.92 139.7) (xy 121.92 142.24)
		)
		(stroke
			(width 0)
			(type default)
		)
	)
	(wire
		(pts
			(xy 124.46 283.21) (xy 123.19 283.21)
		)
		(stroke
			(width 0)
			(type default)
		)
	)
	(wire
		(pts
			(xy 193.04 213.36) (xy 199.39 213.36)
		)
		(stroke
			(width 0)
			(type default)
		)
	)
	(wire
		(pts
			(xy 93.98 166.37) (xy 93.98 168.91)
		)
		(stroke
			(width 0)
			(type default)
		)
	)
	(wire
		(pts
			(xy 231.14 125.73) (xy 231.14 128.27)
		)
		(stroke
			(width 0)
			(type default)
		)
	)
	(wire
		(pts
			(xy 123.19 280.67) (xy 123.19 278.13)
		)
		(stroke
			(width 0)
			(type default)
		)
	)
	(wire
		(pts
			(xy 176.53 157.48) (xy 186.69 157.48)
		)
		(stroke
			(width 0)
			(type default)
		)
	)
	(wire
		(pts
			(xy 199.39 165.1) (xy 199.39 167.64)
		)
		(stroke
			(width 0)
			(type default)
		)
	)
	(wire
		(pts
			(xy 176.53 125.73) (xy 176.53 139.7)
		)
		(stroke
			(width 0)
			(type default)
		)
	)
	(wire
		(pts
			(xy 111.76 193.04) (xy 116.84 193.04)
		)
		(stroke
			(width 0)
			(type default)
		)
	)
	(wire
		(pts
			(xy 180.34 125.73) (xy 186.69 125.73)
		)
		(stroke
			(width 0)
			(type default)
		)
	)
	(wire
		(pts
			(xy 207.01 289.56) (xy 207.01 292.1)
		)
		(stroke
			(width 0)
			(type default)
		)
	)
	(wire
		(pts
			(xy 199.39 213.36) (xy 199.39 217.17)
		)
		(stroke
			(width 0)
			(type default)
		)
	)
	(wire
		(pts
			(xy 199.39 133.35) (xy 199.39 134.62)
		)
		(stroke
			(width 0)
			(type default)
		)
	)
	(wire
		(pts
			(xy 180.34 175.26) (xy 186.69 175.26)
		)
		(stroke
			(width 0)
			(type default)
		)
	)
	(wire
		(pts
			(xy 193.04 157.48) (xy 199.39 157.48)
		)
		(stroke
			(width 0)
			(type default)
		)
	)
	(wire
		(pts
			(xy 105.41 193.04) (xy 111.76 193.04)
		)
		(stroke
			(width 0)
			(type default)
		)
	)
	(wire
		(pts
			(xy 176.53 193.04) (xy 179.07 193.04)
		)
		(stroke
			(width 0)
			(type default)
		)
	)
	(wire
		(pts
			(xy 101.6 276.86) (xy 101.6 279.4)
		)
		(stroke
			(width 0)
			(type default)
		)
	)
	(wire
		(pts
			(xy 180.34 160.02) (xy 176.53 160.02)
		)
		(stroke
			(width 0)
			(type default)
		)
	)
	(wire
		(pts
			(xy 193.04 213.36) (xy 193.04 217.17)
		)
		(stroke
			(width 0)
			(type default)
		)
	)
	(wire
		(pts
			(xy 186.69 193.04) (xy 193.04 193.04)
		)
		(stroke
			(width 0)
			(type default)
		)
	)
	(wire
		(pts
			(xy 186.69 125.73) (xy 193.04 125.73)
		)
		(stroke
			(width 0)
			(type default)
		)
	)
	(wire
		(pts
			(xy 105.41 139.7) (xy 100.33 139.7)
		)
		(stroke
			(width 0)
			(type default)
		)
	)
	(wire
		(pts
			(xy 196.85 281.94) (xy 199.39 281.94)
		)
		(stroke
			(width 0)
			(type default)
		)
	)
	(wire
		(pts
			(xy 111.76 139.7) (xy 105.41 139.7)
		)
		(stroke
			(width 0)
			(type default)
		)
	)
	(wire
		(pts
			(xy 205.74 125.73) (xy 205.74 128.27)
		)
		(stroke
			(width 0)
			(type default)
		)
	)
	(wire
		(pts
			(xy 193.04 175.26) (xy 193.04 177.8)
		)
		(stroke
			(width 0)
			(type default)
		)
	)
	(wire
		(pts
			(xy 180.34 125.73) (xy 180.34 128.27)
		)
		(stroke
			(width 0)
			(type default)
		)
	)
	(wire
		(pts
			(xy 88.9 148.59) (xy 88.9 151.13)
		)
		(stroke
			(width 0)
			(type default)
		)
	)
	(wire
		(pts
			(xy 205.74 175.26) (xy 205.74 177.8)
		)
		(stroke
			(width 0)
			(type default)
		)
	)
	(wire
		(pts
			(xy 116.84 157.48) (xy 116.84 161.29)
		)
		(stroke
			(width 0)
			(type default)
		)
	)
	(wire
		(pts
			(xy 199.39 125.73) (xy 199.39 128.27)
		)
		(stroke
			(width 0)
			(type default)
		)
	)
	(wire
		(pts
			(xy 229.87 208.28) (xy 229.87 213.36)
		)
		(stroke
			(width 0)
			(type default)
		)
	)
	(wire
		(pts
			(xy 124.46 280.67) (xy 123.19 280.67)
		)
		(stroke
			(width 0)
			(type default)
		)
	)
	(wire
		(pts
			(xy 116.84 175.26) (xy 121.92 175.26)
		)
		(stroke
			(width 0)
			(type default)
		)
	)
	(wire
		(pts
			(xy 100.33 139.7) (xy 100.33 143.51)
		)
		(stroke
			(width 0)
			(type default)
		)
	)
	(wire
		(pts
			(xy 217.17 274.32) (xy 217.17 276.86)
		)
		(stroke
			(width 0)
			(type default)
		)
	)
	(wire
		(pts
			(xy 186.69 149.86) (xy 186.69 152.4)
		)
		(stroke
			(width 0)
			(type default)
		)
	)
	(wire
		(pts
			(xy 116.84 139.7) (xy 116.84 143.51)
		)
		(stroke
			(width 0)
			(type default)
		)
	)
	(wire
		(pts
			(xy 186.69 213.36) (xy 186.69 217.17)
		)
		(stroke
			(width 0)
			(type default)
		)
	)
	(wire
		(pts
			(xy 217.17 208.28) (xy 217.17 209.55)
		)
		(stroke
			(width 0)
			(type default)
		)
	)
	(wire
		(pts
			(xy 186.69 125.73) (xy 186.69 128.27)
		)
		(stroke
			(width 0)
			(type default)
		)
	)
	(wire
		(pts
			(xy 176.53 142.24) (xy 176.53 144.78)
		)
		(stroke
			(width 0)
			(type default)
		)
	)
	(wire
		(pts
			(xy 237.49 125.73) (xy 237.49 128.27)
		)
		(stroke
			(width 0)
			(type default)
		)
	)
	(wire
		(pts
			(xy 205.74 182.88) (xy 205.74 184.15)
		)
		(stroke
			(width 0)
			(type default)
		)
	)
	(wire
		(pts
			(xy 116.84 148.59) (xy 116.84 151.13)
		)
		(stroke
			(width 0)
			(type default)
		)
	)
	(wire
		(pts
			(xy 100.33 193.04) (xy 105.41 193.04)
		)
		(stroke
			(width 0)
			(type default)
		)
	)
	(wire
		(pts
			(xy 176.53 195.58) (xy 179.07 195.58)
		)
		(stroke
			(width 0)
			(type default)
		)
	)
	(wire
		(pts
			(xy 116.84 222.25) (xy 116.84 224.79)
		)
		(stroke
			(width 0)
			(type default)
		)
	)
	(wire
		(pts
			(xy 88.9 193.04) (xy 100.33 193.04)
		)
		(stroke
			(width 0)
			(type default)
		)
	)
	(wire
		(pts
			(xy 219.71 193.04) (xy 229.87 193.04)
		)
		(stroke
			(width 0)
			(type default)
		)
	)
	(wire
		(pts
			(xy 199.39 157.48) (xy 199.39 160.02)
		)
		(stroke
			(width 0)
			(type default)
		)
	)
	(wire
		(pts
			(xy 176.53 220.98) (xy 176.53 224.79)
		)
		(stroke
			(width 0)
			(type default)
		)
	)
	(wire
		(pts
			(xy 100.33 148.59) (xy 100.33 151.13)
		)
		(stroke
			(width 0)
			(type default)
		)
	)
	(wire
		(pts
			(xy 205.74 222.25) (xy 205.74 224.79)
		)
		(stroke
			(width 0)
			(type default)
		)
	)
	(wire
		(pts
			(xy 176.53 142.24) (xy 180.34 142.24)
		)
		(stroke
			(width 0)
			(type default)
		)
	)
	(wire
		(pts
			(xy 180.34 161.29) (xy 180.34 160.02)
		)
		(stroke
			(width 0)
			(type default)
		)
	)
	(wire
		(pts
			(xy 93.98 139.7) (xy 88.9 139.7)
		)
		(stroke
			(width 0)
			(type default)
		)
	)
	(wire
		(pts
			(xy 193.04 201.93) (xy 193.04 203.2)
		)
		(stroke
			(width 0)
			(type default)
		)
	)
	(wire
		(pts
			(xy 229.87 213.36) (xy 233.68 213.36)
		)
		(stroke
			(width 0)
			(type default)
		)
	)
	(wire
		(pts
			(xy 111.76 222.25) (xy 111.76 224.79)
		)
		(stroke
			(width 0)
			(type default)
		)
	)
	(wire
		(pts
			(xy 111.76 175.26) (xy 111.76 179.07)
		)
		(stroke
			(width 0)
			(type default)
		)
	)
	(wire
		(pts
			(xy 212.09 133.35) (xy 212.09 134.62)
		)
		(stroke
			(width 0)
			(type default)
		)
	)
	(wire
		(pts
			(xy 224.79 133.35) (xy 224.79 134.62)
		)
		(stroke
			(width 0)
			(type default)
		)
	)
	(wire
		(pts
			(xy 214.63 175.26) (xy 214.63 193.04)
		)
		(stroke
			(width 0)
			(type default)
		)
	)
	(wire
		(pts
			(xy 93.98 157.48) (xy 93.98 161.29)
		)
		(stroke
			(width 0)
			(type default)
		)
	)
	(wire
		(pts
			(xy 246.38 214.63) (xy 250.19 214.63)
		)
		(stroke
			(width 0)
			(type default)
		)
	)
	(wire
		(pts
			(xy 100.33 157.48) (xy 93.98 157.48)
		)
		(stroke
			(width 0)
			(type default)
		)
	)
	(wire
		(pts
			(xy 116.84 213.36) (xy 116.84 217.17)
		)
		(stroke
			(width 0)
			(type default)
		)
	)
	(wire
		(pts
			(xy 212.09 165.1) (xy 212.09 167.64)
		)
		(stroke
			(width 0)
			(type default)
		)
	)
	(wire
		(pts
			(xy 180.34 166.37) (xy 180.34 167.64)
		)
		(stroke
			(width 0)
			(type default)
		)
	)
	(wire
		(pts
			(xy 193.04 193.04) (xy 193.04 196.85)
		)
		(stroke
			(width 0)
			(type default)
		)
	)
	(wire
		(pts
			(xy 204.47 281.94) (xy 207.01 281.94)
		)
		(stroke
			(width 0)
			(type default)
		)
	)
	(wire
		(pts
			(xy 186.69 175.26) (xy 193.04 175.26)
		)
		(stroke
			(width 0)
			(type default)
		)
	)
	(wire
		(pts
			(xy 116.84 276.86) (xy 116.84 278.13)
		)
		(stroke
			(width 0)
			(type default)
		)
	)
	(wire
		(pts
			(xy 93.98 148.59) (xy 93.98 151.13)
		)
		(stroke
			(width 0)
			(type default)
		)
	)
	(wire
		(pts
			(xy 237.49 133.35) (xy 237.49 134.62)
		)
		(stroke
			(width 0)
			(type default)
		)
	)
	(wire
		(pts
			(xy 199.39 175.26) (xy 205.74 175.26)
		)
		(stroke
			(width 0)
			(type default)
		)
	)
	(wire
		(pts
			(xy 180.34 182.88) (xy 180.34 184.15)
		)
		(stroke
			(width 0)
			(type default)
		)
	)
	(wire
		(pts
			(xy 116.84 166.37) (xy 116.84 168.91)
		)
		(stroke
			(width 0)
			(type default)
		)
	)
	(wire
		(pts
			(xy 176.53 175.26) (xy 176.53 177.8)
		)
		(stroke
			(width 0)
			(type default)
		)
	)
	(wire
		(pts
			(xy 186.69 142.24) (xy 187.96 142.24)
		)
		(stroke
			(width 0)
			(type default)
		)
	)
	(wire
		(pts
			(xy 186.69 182.88) (xy 186.69 184.15)
		)
		(stroke
			(width 0)
			(type default)
		)
	)
	(wire
		(pts
			(xy 176.53 213.36) (xy 186.69 213.36)
		)
		(stroke
			(width 0)
			(type default)
		)
	)
	(wire
		(pts
			(xy 199.39 157.48) (xy 203.2 157.48)
		)
		(stroke
			(width 0)
			(type default)
		)
	)
	(wire
		(pts
			(xy 186.69 142.24) (xy 186.69 144.78)
		)
		(stroke
			(width 0)
			(type default)
		)
	)
	(wire
		(pts
			(xy 236.22 208.28) (xy 229.87 208.28)
		)
		(stroke
			(width 0)
			(type default)
		)
	)
	(wire
		(pts
			(xy 207.01 281.94) (xy 207.01 284.48)
		)
		(stroke
			(width 0)
			(type default)
		)
	)
	(wire
		(pts
			(xy 116.84 175.26) (xy 116.84 179.07)
		)
		(stroke
			(width 0)
			(type default)
		)
	)
	(wire
		(pts
			(xy 231.14 125.73) (xy 237.49 125.73)
		)
		(stroke
			(width 0)
			(type default)
		)
	)
	(wire
		(pts
			(xy 116.84 278.13) (xy 116.84 279.4)
		)
		(stroke
			(width 0)
			(type default)
		)
	)
	(wire
		(pts
			(xy 193.04 222.25) (xy 193.04 224.79)
		)
		(stroke
			(width 0)
			(type default)
		)
	)
	(wire
		(pts
			(xy 205.74 133.35) (xy 205.74 134.62)
		)
		(stroke
			(width 0)
			(type default)
		)
	)
	(wire
		(pts
			(xy 93.98 139.7) (xy 93.98 143.51)
		)
		(stroke
			(width 0)
			(type default)
		)
	)
	(wire
		(pts
			(xy 121.92 139.7) (xy 116.84 139.7)
		)
		(stroke
			(width 0)
			(type default)
		)
	)
	(wire
		(pts
			(xy 121.92 157.48) (xy 116.84 157.48)
		)
		(stroke
			(width 0)
			(type default)
		)
	)
	(wire
		(pts
			(xy 208.28 157.48) (xy 212.09 157.48)
		)
		(stroke
			(width 0)
			(type default)
		)
	)
	(wire
		(pts
			(xy 186.69 165.1) (xy 186.69 167.64)
		)
		(stroke
			(width 0)
			(type default)
		)
	)
	(wire
		(pts
			(xy 121.92 220.98) (xy 121.92 224.79)
		)
		(stroke
			(width 0)
			(type default)
		)
	)
	(wire
		(pts
			(xy 193.04 125.73) (xy 199.39 125.73)
		)
		(stroke
			(width 0)
			(type default)
		)
	)
	(wire
		(pts
			(xy 88.9 173.99) (xy 88.9 175.26)
		)
		(stroke
			(width 0)
			(type default)
		)
	)
	(wire
		(pts
			(xy 193.04 133.35) (xy 193.04 134.62)
		)
		(stroke
			(width 0)
			(type default)
		)
	)
	(wire
		(pts
			(xy 105.41 157.48) (xy 105.41 161.29)
		)
		(stroke
			(width 0)
			(type default)
		)
	)
	(text "Hysteresis:\n* Threshold low -> high: 0.366V\n* Threshold high -> low: 0.296V"
		(exclude_from_sim no)
		(at 229.87 229.87 0)
		(effects
			(font
				(size 1.27 1.27)
			)
			(justify left bottom)
		)
	)
	(text "Thunderbolt Controller - Power"
		(exclude_from_sim no)
		(at 127 110.49 0)
		(effects
			(font
				(size 2.54 2.54)
				(thickness 0.508)
				(bold yes)
			)
			(justify left bottom)
		)
	)
	(label "VCC_0P9"
		(at 229.87 193.04 180)
		(fields_autoplaced yes)
		(effects
			(font
				(size 1.27 1.27)
			)
			(justify right bottom)
		)
	)
	(global_label "3V3_SYS"
		(shape input)
		(at 187.96 142.24 0)
		(fields_autoplaced yes)
		(effects
			(font
				(size 1.27 1.27)
			)
			(justify left)
		)
		(property "Intersheetrefs" "${INTERSHEET_REFS}"
			(at 198.356 142.1606 0)
			(effects
				(font
					(size 1.27 1.27)
				)
				(justify left)
				(hide yes)
			)
		)
	)
	(global_label "3V3_SYS"
		(shape input)
		(at 217.17 208.28 90)
		(fields_autoplaced yes)
		(effects
			(font
				(size 1.27 1.27)
			)
			(justify left)
		)
		(property "Intersheetrefs" "${INTERSHEET_REFS}"
			(at 217.0906 197.884 90)
			(effects
				(font
					(size 1.27 1.27)
				)
				(justify left)
				(hide yes)
			)
		)
	)
	(global_label "0P9_BUFFERED"
		(shape output)
		(at 250.19 214.63 0)
		(fields_autoplaced yes)
		(effects
			(font
				(size 1.27 1.27)
			)
			(justify left)
		)
		(property "Intersheetrefs" "${INTERSHEET_REFS}"
			(at 266.8755 214.5506 0)
			(effects
				(font
					(size 1.27 1.27)
				)
				(justify left)
				(hide yes)
			)
		)
	)
	(global_label "3V3_SYS"
		(shape input)
		(at 116.84 276.86 90)
		(fields_autoplaced yes)
		(effects
			(font
				(size 1.27 1.27)
			)
			(justify left)
		)
		(property "Intersheetrefs" "${INTERSHEET_REFS}"
			(at 116.7606 266.464 90)
			(effects
				(font
					(size 1.27 1.27)
				)
				(justify left)
				(hide yes)
			)
		)
	)
	(global_label "0P9_BUFFERED"
		(shape input)
		(at 196.85 281.94 180)
		(fields_autoplaced yes)
		(effects
			(font
				(size 1.27 1.27)
			)
			(justify right)
		)
		(property "Intersheetrefs" "${INTERSHEET_REFS}"
			(at 180.1645 281.8606 0)
			(effects
				(font
					(size 1.27 1.27)
				)
				(justify right)
				(hide yes)
			)
		)
	)
	(global_label "3V3_SYS"
		(shape input)
		(at 241.3 125.73 0)
		(fields_autoplaced yes)
		(effects
			(font
				(size 1.27 1.27)
			)
			(justify left)
		)
		(property "Intersheetrefs" "${INTERSHEET_REFS}"
			(at 251.696 125.6506 0)
			(effects
				(font
					(size 1.27 1.27)
				)
				(justify left)
				(hide yes)
			)
		)
	)
	(global_label "3V3_SYS"
		(shape input)
		(at 217.17 257.81 90)
		(fields_autoplaced yes)
		(effects
			(font
				(size 1.27 1.27)
			)
			(justify left)
		)
		(property "Intersheetrefs" "${INTERSHEET_REFS}"
			(at 217.0906 247.414 90)
			(effects
				(font
					(size 1.27 1.27)
				)
				(justify left)
				(hide yes)
			)
		)
	)
	(global_label "3V3_SYS"
		(shape input)
		(at 217.17 157.48 0)
		(fields_autoplaced yes)
		(effects
			(font
				(size 1.27 1.27)
			)
			(justify left)
		)
		(property "Intersheetrefs" "${INTERSHEET_REFS}"
			(at 227.566 157.4006 0)
			(effects
				(font
					(size 1.27 1.27)
				)
				(justify left)
				(hide yes)
			)
		)
	)
	(global_label "3V3_SYS"
		(shape input)
		(at 101.6 276.86 90)
		(fields_autoplaced yes)
		(effects
			(font
				(size 1.27 1.27)
			)
			(justify left)
		)
		(property "Intersheetrefs" "${INTERSHEET_REFS}"
			(at 101.6 265.892 90)
			(effects
				(font
					(size 1.27 1.27)
				)
				(justify left)
				(hide yes)
			)
		)
	)
	(symbol
		(lib_id "antmicroCapacitors0402:C_1u_0402")
		(at 199.39 182.88 90)
		(unit 1)
		(exclude_from_sim no)
		(in_bom yes)
		(on_board yes)
		(dnp no)
		(property "Reference" "C84"
			(at 200.025 178.435 90)
			(effects
				(font
					(size 1.27 1.27)
					(thickness 0.15)
				)
				(justify right)
			)
		)
		(property "Value" "C_1u_0402"
			(at 209.55 162.56 0)
			(effects
				(font
					(size 1.27 1.27)
					(thickness 0.15)
				)
				(justify left bottom)
				(hide yes)
			)
		)
		(property "Footprint" "antmicro-footprints:C_0402_1005Metric"
			(at 212.09 162.56 0)
			(effects
				(font
					(size 1.27 1.27)
					(thickness 0.15)
				)
				(justify left bottom)
				(hide yes)
			)
		)
		(property "Datasheet" "https://product.tdk.com/en/search/capacitor/ceramic/mlcc/info?part_no=C1005X6S1A105K050BC"
			(at 214.63 162.56 0)
			(effects
				(font
					(size 1.27 1.27)
					(thickness 0.15)
				)
				(justify left bottom)
				(hide yes)
			)
		)
		(property "Description" ""
			(at 199.39 182.88 0)
			(effects
				(font
					(size 1.27 1.27)
				)
				(hide yes)
			)
		)
		(property "MPN" "C1005X6S1A105K050BC"
			(at 217.17 162.56 0)
			(effects
				(font
					(size 1.27 1.27)
					(thickness 0.15)
				)
				(justify left bottom)
				(hide yes)
			)
		)
		(property "Manufacturer" "TDK"
			(at 219.71 162.56 0)
			(effects
				(font
					(size 1.27 1.27)
					(thickness 0.15)
				)
				(justify left bottom)
				(hide yes)
			)
		)
		(property "License" "Apache-2.0"
			(at 222.25 162.56 0)
			(effects
				(font
					(size 1.27 1.27)
					(thickness 0.15)
				)
				(justify left bottom)
				(hide yes)
			)
		)
		(property "Val" "1u"
			(at 200.025 182.245 90)
			(effects
				(font
					(size 1.27 1.27)
					(thickness 0.15)
				)
				(justify right)
			)
		)
		(property "Voltage" ""
			(at 227.33 162.56 0)
			(effects
				(font
					(size 1.27 1.27)
				)
				(justify left bottom)
				(hide yes)
			)
		)
		(property "Dielectric" ""
			(at 229.87 162.56 0)
			(effects
				(font
					(size 1.27 1.27)
				)
				(justify left bottom)
				(hide yes)
			)
		)
		(property "Author" "Antmicro"
			(at 224.79 162.56 0)
			(effects
				(font
					(size 1.27 1.27)
					(thickness 0.15)
				)
				(justify left bottom)
				(hide yes)
			)
		)
		(pin "1"
		)
		(pin "2"
		)
		(instances
			(project "thunderbolt-gpu-adapter"
				(path ""
					(reference "C84")
					(unit 1)
				)
			)
		)
	)
	(symbol
		(lib_id "antmicropower:GND")
		(at 100.33 168.91 0)
		(unit 1)
		(exclude_from_sim no)
		(in_bom yes)
		(on_board yes)
		(dnp no)
		(property "Reference" "#PWR084"
			(at 100.33 175.26 0)
			(effects
				(font
					(size 1.27 1.27)
				)
				(hide yes)
			)
		)
		(property "Value" "GND"
			(at 100.33 172.72 0)
			(effects
				(font
					(size 1.27 1.27)
				)
			)
		)
		(property "Footprint" ""
			(at 100.33 168.91 0)
			(effects
				(font
					(size 1.27 1.27)
				)
				(hide yes)
			)
		)
		(property "Datasheet" ""
			(at 100.33 168.91 0)
			(effects
				(font
					(size 1.27 1.27)
				)
				(hide yes)
			)
		)
		(property "Description" ""
			(at 100.33 168.91 0)
			(effects
				(font
					(size 1.27 1.27)
				)
				(hide yes)
			)
		)
		(property "Author" "Antmicro"
			(at 109.22 176.53 0)
			(effects
				(font
					(size 1.27 1.27)
					(thickness 0.15)
				)
				(justify left bottom)
				(hide yes)
			)
		)
		(property "License" "Apache-2.0"
			(at 109.22 179.07 0)
			(effects
				(font
					(size 1.27 1.27)
					(thickness 0.15)
				)
				(justify left bottom)
				(hide yes)
			)
		)
		(pin "1"
		)
		(instances
			(project "thunderbolt-gpu-adapter"
				(path ""
					(reference "#PWR084")
					(unit 1)
				)
			)
		)
	)
	(symbol
		(lib_id "antmicroCapacitors0402:C_100n_0402")
		(at 193.04 133.35 90)
		(unit 1)
		(exclude_from_sim no)
		(in_bom yes)
		(on_board yes)
		(dnp no)
		(property "Reference" "C93"
			(at 193.675 128.905 90)
			(effects
				(font
					(size 1.27 1.27)
					(thickness 0.15)
				)
				(justify right)
			)
		)
		(property "Value" "C_100n_0402"
			(at 203.2 113.03 0)
			(effects
				(font
					(size 1.27 1.27)
					(thickness 0.15)
				)
				(justify left bottom)
				(hide yes)
			)
		)
		(property "Footprint" "antmicro-footprints:C_0402_1005Metric"
			(at 205.74 113.03 0)
			(effects
				(font
					(size 1.27 1.27)
					(thickness 0.15)
				)
				(justify left bottom)
				(hide yes)
			)
		)
		(property "Datasheet" "https://www.murata.com/products/productdetail?partno=GRM155R61H104KE14%23"
			(at 208.28 113.03 0)
			(effects
				(font
					(size 1.27 1.27)
					(thickness 0.15)
				)
				(justify left bottom)
				(hide yes)
			)
		)
		(property "Description" ""
			(at 193.04 133.35 0)
			(effects
				(font
					(size 1.27 1.27)
				)
				(hide yes)
			)
		)
		(property "MPN" "GRM155R61H104KE14D"
			(at 210.82 113.03 0)
			(effects
				(font
					(size 1.27 1.27)
					(thickness 0.15)
				)
				(justify left bottom)
				(hide yes)
			)
		)
		(property "Manufacturer" "Murata"
			(at 213.36 113.03 0)
			(effects
				(font
					(size 1.27 1.27)
					(thickness 0.15)
				)
				(justify left bottom)
				(hide yes)
			)
		)
		(property "License" "Apache-2.0"
			(at 215.9 113.03 0)
			(effects
				(font
					(size 1.27 1.27)
					(thickness 0.15)
				)
				(justify left bottom)
				(hide yes)
			)
		)
		(property "Val" "100n"
			(at 193.675 132.715 90)
			(effects
				(font
					(size 1.27 1.27)
					(thickness 0.15)
				)
				(justify right)
			)
		)
		(property "Voltage" "50V"
			(at 220.98 113.03 0)
			(effects
				(font
					(size 1.27 1.27)
				)
				(justify left bottom)
				(hide yes)
			)
		)
		(property "Dielectric" "X5R"
			(at 223.52 113.03 0)
			(effects
				(font
					(size 1.27 1.27)
				)
				(justify left bottom)
				(hide yes)
			)
		)
		(property "Author" "Antmicro"
			(at 218.44 113.03 0)
			(effects
				(font
					(size 1.27 1.27)
					(thickness 0.15)
				)
				(justify left bottom)
				(hide yes)
			)
		)
		(pin "1"
		)
		(pin "2"
		)
		(instances
			(project "thunderbolt-gpu-adapter"
				(path ""
					(reference "C93")
					(unit 1)
				)
			)
		)
	)
	(symbol
		(lib_id "antmicroCapacitors0402:C_100n_0402")
		(at 205.74 133.35 90)
		(unit 1)
		(exclude_from_sim no)
		(in_bom yes)
		(on_board yes)
		(dnp no)
		(property "Reference" "C149"
			(at 206.375 128.905 90)
			(effects
				(font
					(size 1.27 1.27)
					(thickness 0.15)
				)
				(justify right)
			)
		)
		(property "Value" "C_100n_0402"
			(at 215.9 113.03 0)
			(effects
				(font
					(size 1.27 1.27)
					(thickness 0.15)
				)
				(justify left bottom)
				(hide yes)
			)
		)
		(property "Footprint" "antmicro-footprints:C_0402_1005Metric"
			(at 218.44 113.03 0)
			(effects
				(font
					(size 1.27 1.27)
					(thickness 0.15)
				)
				(justify left bottom)
				(hide yes)
			)
		)
		(property "Datasheet" "https://www.murata.com/products/productdetail?partno=GRM155R61H104KE14%23"
			(at 220.98 113.03 0)
			(effects
				(font
					(size 1.27 1.27)
					(thickness 0.15)
				)
				(justify left bottom)
				(hide yes)
			)
		)
		(property "Description" ""
			(at 205.74 133.35 0)
			(effects
				(font
					(size 1.27 1.27)
				)
				(hide yes)
			)
		)
		(property "MPN" "GRM155R61H104KE14D"
			(at 223.52 113.03 0)
			(effects
				(font
					(size 1.27 1.27)
					(thickness 0.15)
				)
				(justify left bottom)
				(hide yes)
			)
		)
		(property "Manufacturer" "Murata"
			(at 226.06 113.03 0)
			(effects
				(font
					(size 1.27 1.27)
					(thickness 0.15)
				)
				(justify left bottom)
				(hide yes)
			)
		)
		(property "License" "Apache-2.0"
			(at 228.6 113.03 0)
			(effects
				(font
					(size 1.27 1.27)
					(thickness 0.15)
				)
				(justify left bottom)
				(hide yes)
			)
		)
		(property "Val" "100n"
			(at 206.375 132.715 90)
			(effects
				(font
					(size 1.27 1.27)
					(thickness 0.15)
				)
				(justify right)
			)
		)
		(property "Voltage" "50V"
			(at 233.68 113.03 0)
			(effects
				(font
					(size 1.27 1.27)
				)
				(justify left bottom)
				(hide yes)
			)
		)
		(property "Dielectric" "X5R"
			(at 236.22 113.03 0)
			(effects
				(font
					(size 1.27 1.27)
				)
				(justify left bottom)
				(hide yes)
			)
		)
		(property "Author" "Antmicro"
			(at 231.14 113.03 0)
			(effects
				(font
					(size 1.27 1.27)
					(thickness 0.15)
				)
				(justify left bottom)
				(hide yes)
			)
		)
		(pin "1"
		)
		(pin "2"
		)
		(instances
			(project "thunderbolt-gpu-adapter"
				(path ""
					(reference "C149")
					(unit 1)
				)
			)
		)
	)
	(symbol
		(lib_id "antmicroCapacitors0402:C_1u_0402")
		(at 111.76 184.15 90)
		(unit 1)
		(exclude_from_sim no)
		(in_bom yes)
		(on_board yes)
		(dnp no)
		(fields_autoplaced yes)
		(property "Reference" "C51"
			(at 109.22 180.3336 90)
			(effects
				(font
					(size 1.27 1.27)
					(thickness 0.15)
				)
				(justify left)
			)
		)
		(property "Value" "C_1u_0402"
			(at 121.92 163.83 0)
			(effects
				(font
					(size 1.27 1.27)
					(thickness 0.15)
				)
				(justify left bottom)
				(hide yes)
			)
		)
		(property "Footprint" "antmicro-footprints:C_0402_1005Metric"
			(at 124.46 163.83 0)
			(effects
				(font
					(size 1.27 1.27)
					(thickness 0.15)
				)
				(justify left bottom)
				(hide yes)
			)
		)
		(property "Datasheet" "https://product.tdk.com/en/search/capacitor/ceramic/mlcc/info?part_no=C1005X6S1A105K050BC"
			(at 127 163.83 0)
			(effects
				(font
					(size 1.27 1.27)
					(thickness 0.15)
				)
				(justify left bottom)
				(hide yes)
			)
		)
		(property "Description" ""
			(at 111.76 184.15 0)
			(effects
				(font
					(size 1.27 1.27)
				)
				(hide yes)
			)
		)
		(property "MPN" "C1005X6S1A105K050BC"
			(at 129.54 163.83 0)
			(effects
				(font
					(size 1.27 1.27)
					(thickness 0.15)
				)
				(justify left bottom)
				(hide yes)
			)
		)
		(property "Manufacturer" "TDK"
			(at 132.08 163.83 0)
			(effects
				(font
					(size 1.27 1.27)
					(thickness 0.15)
				)
				(justify left bottom)
				(hide yes)
			)
		)
		(property "License" "Apache-2.0"
			(at 134.62 163.83 0)
			(effects
				(font
					(size 1.27 1.27)
					(thickness 0.15)
				)
				(justify left bottom)
				(hide yes)
			)
		)
		(property "Val" "1u"
			(at 109.22 182.8736 90)
			(effects
				(font
					(size 1.27 1.27)
					(thickness 0.15)
				)
				(justify left)
			)
		)
		(property "Voltage" ""
			(at 139.7 163.83 0)
			(effects
				(font
					(size 1.27 1.27)
				)
				(justify left bottom)
				(hide yes)
			)
		)
		(property "Dielectric" ""
			(at 142.24 163.83 0)
			(effects
				(font
					(size 1.27 1.27)
				)
				(justify left bottom)
				(hide yes)
			)
		)
		(property "Author" "Antmicro"
			(at 137.16 163.83 0)
			(effects
				(font
					(size 1.27 1.27)
					(thickness 0.15)
				)
				(justify left bottom)
				(hide yes)
			)
		)
		(pin "1"
		)
		(pin "2"
		)
		(instances
			(project "thunderbolt-gpu-adapter"
				(path ""
					(reference "C51")
					(unit 1)
				)
			)
		)
	)
	(symbol
		(lib_id "antmicroLEDIndicationDiscrete:LED_G_0603_KP-1608CGCK")
		(at 217.17 266.7 90)
		(unit 1)
		(exclude_from_sim no)
		(in_bom yes)
		(on_board yes)
		(dnp no)
		(fields_autoplaced yes)
		(property "Reference" "D4"
			(at 219.71 262.89 90)
			(effects
				(font
					(size 1.27 1.27)
					(thickness 0.15)
				)
				(justify right)
			)
		)
		(property "Value" "LED_G_0603_KP-1608CGCK"
			(at 213.36 261.6201 90)
			(effects
				(font
					(size 1.27 1.27)
					(thickness 0.15)
				)
				(justify left)
				(hide yes)
			)
		)
		(property "Footprint" "antmicro-footprints:LED_0603_1608Metric_G"
			(at 227.33 243.84 0)
			(effects
				(font
					(size 1.27 1.27)
					(thickness 0.15)
				)
				(justify left bottom)
				(hide yes)
			)
		)
		(property "Datasheet" "http://www.kingbright.com/attachments/file/psearch//000/00/00/KP-1608CGCK(Ver.23B).pdf"
			(at 229.87 243.84 0)
			(effects
				(font
					(size 1.27 1.27)
					(thickness 0.15)
				)
				(justify left bottom)
				(hide yes)
			)
		)
		(property "Description" ""
			(at 217.17 266.7 0)
			(effects
				(font
					(size 1.27 1.27)
				)
				(hide yes)
			)
		)
		(property "MPN" "KP-1608CGCK"
			(at 232.41 243.84 0)
			(effects
				(font
					(size 1.27 1.27)
					(thickness 0.15)
				)
				(justify left bottom)
				(hide yes)
			)
		)
		(property "Manufacturer" "Kingbright"
			(at 234.95 243.84 0)
			(effects
				(font
					(size 1.27 1.27)
					(thickness 0.15)
				)
				(justify left bottom)
				(hide yes)
			)
		)
		(property "License" "Apache-2.0"
			(at 240.03 243.84 0)
			(effects
				(font
					(size 1.27 1.27)
					(thickness 0.15)
				)
				(justify left bottom)
				(hide yes)
			)
		)
		(property "Author" "Antmicro"
			(at 237.49 243.84 0)
			(effects
				(font
					(size 1.27 1.27)
					(thickness 0.15)
				)
				(justify left bottom)
				(hide yes)
			)
		)
		(property "Color" "Green"
			(at 219.71 265.43 90)
			(effects
				(font
					(size 1.27 1.27)
				)
				(justify right)
			)
		)
		(pin "1"
		)
		(pin "2"
		)
		(instances
			(project "thunderbolt-gpu-adapter"
				(path ""
					(reference "D4")
					(unit 1)
				)
			)
		)
	)
	(symbol
		(lib_id "antmicroResistors0402:R_1k_0402")
		(at 229.87 203.2 90)
		(unit 1)
		(exclude_from_sim no)
		(in_bom yes)
		(on_board yes)
		(dnp no)
		(fields_autoplaced yes)
		(property "Reference" "R135"
			(at 227.33 199.39 90)
			(effects
				(font
					(size 1.27 1.27)
					(thickness 0.15)
				)
				(justify left)
			)
		)
		(property "Value" "R_1k_0402"
			(at 242.57 182.88 0)
			(effects
				(font
					(size 1.27 1.27)
					(thickness 0.15)
				)
				(justify left bottom)
				(hide yes)
			)
		)
		(property "Footprint" "antmicro-footprints:R_0402_1005Metric"
			(at 245.11 182.88 0)
			(effects
				(font
					(size 1.27 1.27)
					(thickness 0.15)
				)
				(justify left bottom)
				(hide yes)
			)
		)
		(property "Datasheet" "https://www.bourns.com/docs/product-datasheets/cr.pdf"
			(at 247.65 182.88 0)
			(effects
				(font
					(size 1.27 1.27)
					(thickness 0.15)
				)
				(justify left bottom)
				(hide yes)
			)
		)
		(property "Description" ""
			(at 229.87 203.2 0)
			(effects
				(font
					(size 1.27 1.27)
				)
				(hide yes)
			)
		)
		(property "MPN" "CR0402-FX-1001GLF"
			(at 250.19 182.88 0)
			(effects
				(font
					(size 1.27 1.27)
					(thickness 0.15)
				)
				(justify left bottom)
				(hide yes)
			)
		)
		(property "Manufacturer" "Bourns"
			(at 252.73 182.88 0)
			(effects
				(font
					(size 1.27 1.27)
					(thickness 0.15)
				)
				(justify left bottom)
				(hide yes)
			)
		)
		(property "License" "Apache-2.0"
			(at 255.27 182.88 0)
			(effects
				(font
					(size 1.27 1.27)
					(thickness 0.15)
				)
				(justify left bottom)
				(hide yes)
			)
		)
		(property "Author" "Antmicro"
			(at 257.81 182.88 0)
			(effects
				(font
					(size 1.27 1.27)
					(thickness 0.15)
				)
				(justify left bottom)
				(hide yes)
			)
		)
		(property "Val" "1k"
			(at 227.33 201.93 90)
			(effects
				(font
					(size 1.27 1.27)
					(thickness 0.15)
				)
				(justify left)
			)
		)
		(property "Tolerance" "1%"
			(at 240.03 182.88 0)
			(effects
				(font
					(size 1.27 1.27)
				)
				(justify left bottom)
				(hide yes)
			)
		)
		(pin "1"
		)
		(pin "2"
		)
		(instances
			(project "thunderbolt-gpu-adapter"
				(path ""
					(reference "R135")
					(unit 1)
				)
			)
		)
	)
	(symbol
		(lib_id "antmicropower:GND")
		(at 199.39 167.64 0)
		(unit 1)
		(exclude_from_sim no)
		(in_bom yes)
		(on_board yes)
		(dnp no)
		(property "Reference" "#PWR0124"
			(at 199.39 173.99 0)
			(effects
				(font
					(size 1.27 1.27)
				)
				(hide yes)
			)
		)
		(property "Value" "GND"
			(at 199.39 171.45 0)
			(effects
				(font
					(size 1.27 1.27)
				)
			)
		)
		(property "Footprint" ""
			(at 199.39 167.64 0)
			(effects
				(font
					(size 1.27 1.27)
				)
				(hide yes)
			)
		)
		(property "Datasheet" ""
			(at 199.39 167.64 0)
			(effects
				(font
					(size 1.27 1.27)
				)
				(hide yes)
			)
		)
		(property "Description" ""
			(at 199.39 167.64 0)
			(effects
				(font
					(size 1.27 1.27)
				)
				(hide yes)
			)
		)
		(property "Author" "Antmicro"
			(at 208.28 175.26 0)
			(effects
				(font
					(size 1.27 1.27)
					(thickness 0.15)
				)
				(justify left bottom)
				(hide yes)
			)
		)
		(property "License" "Apache-2.0"
			(at 208.28 177.8 0)
			(effects
				(font
					(size 1.27 1.27)
					(thickness 0.15)
				)
				(justify left bottom)
				(hide yes)
			)
		)
		(pin "1"
		)
		(instances
			(project "thunderbolt-gpu-adapter"
				(path ""
					(reference "#PWR0124")
					(unit 1)
				)
			)
		)
	)
	(symbol
		(lib_id "antmicropower:GND")
		(at 186.69 134.62 0)
		(unit 1)
		(exclude_from_sim no)
		(in_bom yes)
		(on_board yes)
		(dnp no)
		(property "Reference" "#PWR0119"
			(at 186.69 140.97 0)
			(effects
				(font
					(size 1.27 1.27)
				)
				(hide yes)
			)
		)
		(property "Value" "GND"
			(at 186.69 138.43 0)
			(effects
				(font
					(size 1.27 1.27)
				)
			)
		)
		(property "Footprint" ""
			(at 186.69 134.62 0)
			(effects
				(font
					(size 1.27 1.27)
				)
				(hide yes)
			)
		)
		(property "Datasheet" ""
			(at 186.69 134.62 0)
			(effects
				(font
					(size 1.27 1.27)
				)
				(hide yes)
			)
		)
		(property "Description" ""
			(at 186.69 134.62 0)
			(effects
				(font
					(size 1.27 1.27)
				)
				(hide yes)
			)
		)
		(property "Author" "Antmicro"
			(at 195.58 142.24 0)
			(effects
				(font
					(size 1.27 1.27)
					(thickness 0.15)
				)
				(justify left bottom)
				(hide yes)
			)
		)
		(property "License" "Apache-2.0"
			(at 195.58 144.78 0)
			(effects
				(font
					(size 1.27 1.27)
					(thickness 0.15)
				)
				(justify left bottom)
				(hide yes)
			)
		)
		(pin "1"
		)
		(instances
			(project "thunderbolt-gpu-adapter"
				(path ""
					(reference "#PWR0119")
					(unit 1)
				)
			)
		)
	)
	(symbol
		(lib_id "antmicroCapacitors0402:C_1u_0402")
		(at 111.76 148.59 90)
		(unit 1)
		(exclude_from_sim no)
		(in_bom yes)
		(on_board yes)
		(dnp no)
		(property "Reference" "C64"
			(at 112.395 144.145 90)
			(effects
				(font
					(size 1.27 1.27)
					(thickness 0.15)
				)
				(justify right)
			)
		)
		(property "Value" "C_1u_0402"
			(at 121.92 128.27 0)
			(effects
				(font
					(size 1.27 1.27)
					(thickness 0.15)
				)
				(justify left bottom)
				(hide yes)
			)
		)
		(property "Footprint" "antmicro-footprints:C_0402_1005Metric"
			(at 124.46 128.27 0)
			(effects
				(font
					(size 1.27 1.27)
					(thickness 0.15)
				)
				(justify left bottom)
				(hide yes)
			)
		)
		(property "Datasheet" "https://product.tdk.com/en/search/capacitor/ceramic/mlcc/info?part_no=C1005X6S1A105K050BC"
			(at 127 128.27 0)
			(effects
				(font
					(size 1.27 1.27)
					(thickness 0.15)
				)
				(justify left bottom)
				(hide yes)
			)
		)
		(property "Description" ""
			(at 111.76 148.59 0)
			(effects
				(font
					(size 1.27 1.27)
				)
				(hide yes)
			)
		)
		(property "MPN" "C1005X6S1A105K050BC"
			(at 129.54 128.27 0)
			(effects
				(font
					(size 1.27 1.27)
					(thickness 0.15)
				)
				(justify left bottom)
				(hide yes)
			)
		)
		(property "Manufacturer" "TDK"
			(at 132.08 128.27 0)
			(effects
				(font
					(size 1.27 1.27)
					(thickness 0.15)
				)
				(justify left bottom)
				(hide yes)
			)
		)
		(property "License" "Apache-2.0"
			(at 134.62 128.27 0)
			(effects
				(font
					(size 1.27 1.27)
					(thickness 0.15)
				)
				(justify left bottom)
				(hide yes)
			)
		)
		(property "Val" "1u"
			(at 112.395 147.955 90)
			(effects
				(font
					(size 1.27 1.27)
					(thickness 0.15)
				)
				(justify right)
			)
		)
		(property "Voltage" ""
			(at 139.7 128.27 0)
			(effects
				(font
					(size 1.27 1.27)
				)
				(justify left bottom)
				(hide yes)
			)
		)
		(property "Dielectric" ""
			(at 142.24 128.27 0)
			(effects
				(font
					(size 1.27 1.27)
				)
				(justify left bottom)
				(hide yes)
			)
		)
		(property "Author" "Antmicro"
			(at 137.16 128.27 0)
			(effects
				(font
					(size 1.27 1.27)
					(thickness 0.15)
				)
				(justify left bottom)
				(hide yes)
			)
		)
		(pin "1"
		)
		(pin "2"
		)
		(instances
			(project "thunderbolt-gpu-adapter"
				(path ""
					(reference "C64")
					(unit 1)
				)
			)
		)
	)
	(symbol
		(lib_id "antmicroCapacitors0402:C_1u_0402")
		(at 100.33 148.59 90)
		(unit 1)
		(exclude_from_sim no)
		(in_bom yes)
		(on_board yes)
		(dnp no)
		(property "Reference" "C58"
			(at 100.965 144.145 90)
			(effects
				(font
					(size 1.27 1.27)
					(thickness 0.15)
				)
				(justify right)
			)
		)
		(property "Value" "C_1u_0402"
			(at 110.49 128.27 0)
			(effects
				(font
					(size 1.27 1.27)
					(thickness 0.15)
				)
				(justify left bottom)
				(hide yes)
			)
		)
		(property "Footprint" "antmicro-footprints:C_0402_1005Metric"
			(at 113.03 128.27 0)
			(effects
				(font
					(size 1.27 1.27)
					(thickness 0.15)
				)
				(justify left bottom)
				(hide yes)
			)
		)
		(property "Datasheet" "https://product.tdk.com/en/search/capacitor/ceramic/mlcc/info?part_no=C1005X6S1A105K050BC"
			(at 115.57 128.27 0)
			(effects
				(font
					(size 1.27 1.27)
					(thickness 0.15)
				)
				(justify left bottom)
				(hide yes)
			)
		)
		(property "Description" ""
			(at 100.33 148.59 0)
			(effects
				(font
					(size 1.27 1.27)
				)
				(hide yes)
			)
		)
		(property "MPN" "C1005X6S1A105K050BC"
			(at 118.11 128.27 0)
			(effects
				(font
					(size 1.27 1.27)
					(thickness 0.15)
				)
				(justify left bottom)
				(hide yes)
			)
		)
		(property "Manufacturer" "TDK"
			(at 120.65 128.27 0)
			(effects
				(font
					(size 1.27 1.27)
					(thickness 0.15)
				)
				(justify left bottom)
				(hide yes)
			)
		)
		(property "License" "Apache-2.0"
			(at 123.19 128.27 0)
			(effects
				(font
					(size 1.27 1.27)
					(thickness 0.15)
				)
				(justify left bottom)
				(hide yes)
			)
		)
		(property "Val" "1u"
			(at 100.965 147.955 90)
			(effects
				(font
					(size 1.27 1.27)
					(thickness 0.15)
				)
				(justify right)
			)
		)
		(property "Voltage" ""
			(at 128.27 128.27 0)
			(effects
				(font
					(size 1.27 1.27)
				)
				(justify left bottom)
				(hide yes)
			)
		)
		(property "Dielectric" ""
			(at 130.81 128.27 0)
			(effects
				(font
					(size 1.27 1.27)
				)
				(justify left bottom)
				(hide yes)
			)
		)
		(property "Author" "Antmicro"
			(at 125.73 128.27 0)
			(effects
				(font
					(size 1.27 1.27)
					(thickness 0.15)
				)
				(justify left bottom)
				(hide yes)
			)
		)
		(pin "1"
		)
		(pin "2"
		)
		(instances
			(project "thunderbolt-gpu-adapter"
				(path ""
					(reference "C58")
					(unit 1)
				)
			)
		)
	)
	(symbol
		(lib_id "antmicroCapacitors0402:C_1u_0402")
		(at 88.9 148.59 90)
		(unit 1)
		(exclude_from_sim no)
		(in_bom yes)
		(on_board yes)
		(dnp no)
		(property "Reference" "C53"
			(at 89.535 144.145 90)
			(effects
				(font
					(size 1.27 1.27)
					(thickness 0.15)
				)
				(justify right)
			)
		)
		(property "Value" "C_1u_0402"
			(at 99.06 128.27 0)
			(effects
				(font
					(size 1.27 1.27)
					(thickness 0.15)
				)
				(justify left bottom)
				(hide yes)
			)
		)
		(property "Footprint" "antmicro-footprints:C_0402_1005Metric"
			(at 101.6 128.27 0)
			(effects
				(font
					(size 1.27 1.27)
					(thickness 0.15)
				)
				(justify left bottom)
				(hide yes)
			)
		)
		(property "Datasheet" "https://product.tdk.com/en/search/capacitor/ceramic/mlcc/info?part_no=C1005X6S1A105K050BC"
			(at 104.14 128.27 0)
			(effects
				(font
					(size 1.27 1.27)
					(thickness 0.15)
				)
				(justify left bottom)
				(hide yes)
			)
		)
		(property "Description" ""
			(at 88.9 148.59 0)
			(effects
				(font
					(size 1.27 1.27)
				)
				(hide yes)
			)
		)
		(property "MPN" "C1005X6S1A105K050BC"
			(at 106.68 128.27 0)
			(effects
				(font
					(size 1.27 1.27)
					(thickness 0.15)
				)
				(justify left bottom)
				(hide yes)
			)
		)
		(property "Manufacturer" "TDK"
			(at 109.22 128.27 0)
			(effects
				(font
					(size 1.27 1.27)
					(thickness 0.15)
				)
				(justify left bottom)
				(hide yes)
			)
		)
		(property "License" "Apache-2.0"
			(at 111.76 128.27 0)
			(effects
				(font
					(size 1.27 1.27)
					(thickness 0.15)
				)
				(justify left bottom)
				(hide yes)
			)
		)
		(property "Val" "1u"
			(at 89.535 147.955 90)
			(effects
				(font
					(size 1.27 1.27)
					(thickness 0.15)
				)
				(justify right)
			)
		)
		(property "Voltage" ""
			(at 116.84 128.27 0)
			(effects
				(font
					(size 1.27 1.27)
				)
				(justify left bottom)
				(hide yes)
			)
		)
		(property "Dielectric" ""
			(at 119.38 128.27 0)
			(effects
				(font
					(size 1.27 1.27)
				)
				(justify left bottom)
				(hide yes)
			)
		)
		(property "Author" "Antmicro"
			(at 114.3 128.27 0)
			(effects
				(font
					(size 1.27 1.27)
					(thickness 0.15)
				)
				(justify left bottom)
				(hide yes)
			)
		)
		(pin "1"
		)
		(pin "2"
		)
		(instances
			(project "thunderbolt-gpu-adapter"
				(path ""
					(reference "C53")
					(unit 1)
				)
			)
		)
	)
	(symbol
		(lib_id "antmicroCapacitors0402:C_1u_0402")
		(at 116.84 222.25 90)
		(unit 1)
		(exclude_from_sim no)
		(in_bom yes)
		(on_board yes)
		(dnp no)
		(fields_autoplaced yes)
		(property "Reference" "C69"
			(at 119.38 218.4336 90)
			(effects
				(font
					(size 1.27 1.27)
					(thickness 0.15)
				)
				(justify right)
			)
		)
		(property "Value" "C_1u_0402"
			(at 127 201.93 0)
			(effects
				(font
					(size 1.27 1.27)
					(thickness 0.15)
				)
				(justify left bottom)
				(hide yes)
			)
		)
		(property "Footprint" "antmicro-footprints:C_0402_1005Metric"
			(at 129.54 201.93 0)
			(effects
				(font
					(size 1.27 1.27)
					(thickness 0.15)
				)
				(justify left bottom)
				(hide yes)
			)
		)
		(property "Datasheet" "https://product.tdk.com/en/search/capacitor/ceramic/mlcc/info?part_no=C1005X6S1A105K050BC"
			(at 132.08 201.93 0)
			(effects
				(font
					(size 1.27 1.27)
					(thickness 0.15)
				)
				(justify left bottom)
				(hide yes)
			)
		)
		(property "Description" ""
			(at 116.84 222.25 0)
			(effects
				(font
					(size 1.27 1.27)
				)
				(hide yes)
			)
		)
		(property "MPN" "C1005X6S1A105K050BC"
			(at 134.62 201.93 0)
			(effects
				(font
					(size 1.27 1.27)
					(thickness 0.15)
				)
				(justify left bottom)
				(hide yes)
			)
		)
		(property "Manufacturer" "TDK"
			(at 137.16 201.93 0)
			(effects
				(font
					(size 1.27 1.27)
					(thickness 0.15)
				)
				(justify left bottom)
				(hide yes)
			)
		)
		(property "License" "Apache-2.0"
			(at 139.7 201.93 0)
			(effects
				(font
					(size 1.27 1.27)
					(thickness 0.15)
				)
				(justify left bottom)
				(hide yes)
			)
		)
		(property "Val" "1u"
			(at 119.38 220.9736 90)
			(effects
				(font
					(size 1.27 1.27)
					(thickness 0.15)
				)
				(justify right)
			)
		)
		(property "Voltage" ""
			(at 144.78 201.93 0)
			(effects
				(font
					(size 1.27 1.27)
				)
				(justify left bottom)
				(hide yes)
			)
		)
		(property "Dielectric" ""
			(at 147.32 201.93 0)
			(effects
				(font
					(size 1.27 1.27)
				)
				(justify left bottom)
				(hide yes)
			)
		)
		(property "Author" "Antmicro"
			(at 142.24 201.93 0)
			(effects
				(font
					(size 1.27 1.27)
					(thickness 0.15)
				)
				(justify left bottom)
				(hide yes)
			)
		)
		(pin "1"
		)
		(pin "2"
		)
		(instances
			(project "thunderbolt-gpu-adapter"
				(path ""
					(reference "C69")
					(unit 1)
				)
			)
		)
	)
	(symbol
		(lib_id "antmicroCapacitors0402:C_1u_0402")
		(at 100.33 166.37 90)
		(unit 1)
		(exclude_from_sim no)
		(in_bom yes)
		(on_board yes)
		(dnp no)
		(property "Reference" "C59"
			(at 100.965 161.925 90)
			(effects
				(font
					(size 1.27 1.27)
					(thickness 0.15)
				)
				(justify right)
			)
		)
		(property "Value" "C_1u_0402"
			(at 110.49 146.05 0)
			(effects
				(font
					(size 1.27 1.27)
					(thickness 0.15)
				)
				(justify left bottom)
				(hide yes)
			)
		)
		(property "Footprint" "antmicro-footprints:C_0402_1005Metric"
			(at 113.03 146.05 0)
			(effects
				(font
					(size 1.27 1.27)
					(thickness 0.15)
				)
				(justify left bottom)
				(hide yes)
			)
		)
		(property "Datasheet" "https://product.tdk.com/en/search/capacitor/ceramic/mlcc/info?part_no=C1005X6S1A105K050BC"
			(at 115.57 146.05 0)
			(effects
				(font
					(size 1.27 1.27)
					(thickness 0.15)
				)
				(justify left bottom)
				(hide yes)
			)
		)
		(property "Description" ""
			(at 100.33 166.37 0)
			(effects
				(font
					(size 1.27 1.27)
				)
				(hide yes)
			)
		)
		(property "MPN" "C1005X6S1A105K050BC"
			(at 118.11 146.05 0)
			(effects
				(font
					(size 1.27 1.27)
					(thickness 0.15)
				)
				(justify left bottom)
				(hide yes)
			)
		)
		(property "Manufacturer" "TDK"
			(at 120.65 146.05 0)
			(effects
				(font
					(size 1.27 1.27)
					(thickness 0.15)
				)
				(justify left bottom)
				(hide yes)
			)
		)
		(property "License" "Apache-2.0"
			(at 123.19 146.05 0)
			(effects
				(font
					(size 1.27 1.27)
					(thickness 0.15)
				)
				(justify left bottom)
				(hide yes)
			)
		)
		(property "Val" "1u"
			(at 100.965 165.735 90)
			(effects
				(font
					(size 1.27 1.27)
					(thickness 0.15)
				)
				(justify right)
			)
		)
		(property "Voltage" ""
			(at 128.27 146.05 0)
			(effects
				(font
					(size 1.27 1.27)
				)
				(justify left bottom)
				(hide yes)
			)
		)
		(property "Dielectric" ""
			(at 130.81 146.05 0)
			(effects
				(font
					(size 1.27 1.27)
				)
				(justify left bottom)
				(hide yes)
			)
		)
		(property "Author" "Antmicro"
			(at 125.73 146.05 0)
			(effects
				(font
					(size 1.27 1.27)
					(thickness 0.15)
				)
				(justify left bottom)
				(hide yes)
			)
		)
		(pin "1"
		)
		(pin "2"
		)
		(instances
			(project "thunderbolt-gpu-adapter"
				(path ""
					(reference "C59")
					(unit 1)
				)
			)
		)
	)
	(symbol
		(lib_id "antmicropower:GND")
		(at 237.49 134.62 0)
		(unit 1)
		(exclude_from_sim no)
		(in_bom yes)
		(on_board yes)
		(dnp no)
		(property "Reference" "#PWR0111"
			(at 237.49 140.97 0)
			(effects
				(font
					(size 1.27 1.27)
				)
				(hide yes)
			)
		)
		(property "Value" "GND"
			(at 237.49 138.43 0)
			(effects
				(font
					(size 1.27 1.27)
				)
			)
		)
		(property "Footprint" ""
			(at 237.49 134.62 0)
			(effects
				(font
					(size 1.27 1.27)
				)
				(hide yes)
			)
		)
		(property "Datasheet" ""
			(at 237.49 134.62 0)
			(effects
				(font
					(size 1.27 1.27)
				)
				(hide yes)
			)
		)
		(property "Description" ""
			(at 237.49 134.62 0)
			(effects
				(font
					(size 1.27 1.27)
				)
				(hide yes)
			)
		)
		(property "Author" "Antmicro"
			(at 246.38 142.24 0)
			(effects
				(font
					(size 1.27 1.27)
					(thickness 0.15)
				)
				(justify left bottom)
				(hide yes)
			)
		)
		(property "License" "Apache-2.0"
			(at 246.38 144.78 0)
			(effects
				(font
					(size 1.27 1.27)
					(thickness 0.15)
				)
				(justify left bottom)
				(hide yes)
			)
		)
		(pin "1"
		)
		(instances
			(project "thunderbolt-gpu-adapter"
				(path ""
					(reference "#PWR0111")
					(unit 1)
				)
			)
		)
	)
	(symbol
		(lib_id "antmicroCapacitors0402:C_1u_0402")
		(at 111.76 201.93 90)
		(unit 1)
		(exclude_from_sim no)
		(in_bom yes)
		(on_board yes)
		(dnp no)
		(property "Reference" "C60"
			(at 112.395 197.485 90)
			(effects
				(font
					(size 1.27 1.27)
					(thickness 0.15)
				)
				(justify right)
			)
		)
		(property "Value" "C_1u_0402"
			(at 121.92 181.61 0)
			(effects
				(font
					(size 1.27 1.27)
					(thickness 0.15)
				)
				(justify left bottom)
				(hide yes)
			)
		)
		(property "Footprint" "antmicro-footprints:C_0402_1005Metric"
			(at 124.46 181.61 0)
			(effects
				(font
					(size 1.27 1.27)
					(thickness 0.15)
				)
				(justify left bottom)
				(hide yes)
			)
		)
		(property "Datasheet" "https://product.tdk.com/en/search/capacitor/ceramic/mlcc/info?part_no=C1005X6S1A105K050BC"
			(at 127 181.61 0)
			(effects
				(font
					(size 1.27 1.27)
					(thickness 0.15)
				)
				(justify left bottom)
				(hide yes)
			)
		)
		(property "Description" ""
			(at 111.76 201.93 0)
			(effects
				(font
					(size 1.27 1.27)
				)
				(hide yes)
			)
		)
		(property "MPN" "C1005X6S1A105K050BC"
			(at 129.54 181.61 0)
			(effects
				(font
					(size 1.27 1.27)
					(thickness 0.15)
				)
				(justify left bottom)
				(hide yes)
			)
		)
		(property "Manufacturer" "TDK"
			(at 132.08 181.61 0)
			(effects
				(font
					(size 1.27 1.27)
					(thickness 0.15)
				)
				(justify left bottom)
				(hide yes)
			)
		)
		(property "License" "Apache-2.0"
			(at 134.62 181.61 0)
			(effects
				(font
					(size 1.27 1.27)
					(thickness 0.15)
				)
				(justify left bottom)
				(hide yes)
			)
		)
		(property "Val" "1u"
			(at 112.395 201.295 90)
			(effects
				(font
					(size 1.27 1.27)
					(thickness 0.15)
				)
				(justify right)
			)
		)
		(property "Voltage" ""
			(at 139.7 181.61 0)
			(effects
				(font
					(size 1.27 1.27)
				)
				(justify left bottom)
				(hide yes)
			)
		)
		(property "Dielectric" ""
			(at 142.24 181.61 0)
			(effects
				(font
					(size 1.27 1.27)
				)
				(justify left bottom)
				(hide yes)
			)
		)
		(property "Author" "Antmicro"
			(at 137.16 181.61 0)
			(effects
				(font
					(size 1.27 1.27)
					(thickness 0.15)
				)
				(justify left bottom)
				(hide yes)
			)
		)
		(pin "1"
		)
		(pin "2"
		)
		(instances
			(project "thunderbolt-gpu-adapter"
				(path ""
					(reference "C60")
					(unit 1)
				)
			)
		)
	)
	(symbol
		(lib_id "antmicropower:GND")
		(at 88.9 151.13 0)
		(unit 1)
		(exclude_from_sim no)
		(in_bom yes)
		(on_board yes)
		(dnp no)
		(property "Reference" "#PWR078"
			(at 88.9 157.48 0)
			(effects
				(font
					(size 1.27 1.27)
				)
				(hide yes)
			)
		)
		(property "Value" "GND"
			(at 88.9 154.94 0)
			(effects
				(font
					(size 1.27 1.27)
				)
			)
		)
		(property "Footprint" ""
			(at 88.9 151.13 0)
			(effects
				(font
					(size 1.27 1.27)
				)
				(hide yes)
			)
		)
		(property "Datasheet" ""
			(at 88.9 151.13 0)
			(effects
				(font
					(size 1.27 1.27)
				)
				(hide yes)
			)
		)
		(property "Description" ""
			(at 88.9 151.13 0)
			(effects
				(font
					(size 1.27 1.27)
				)
				(hide yes)
			)
		)
		(property "Author" "Antmicro"
			(at 97.79 158.75 0)
			(effects
				(font
					(size 1.27 1.27)
					(thickness 0.15)
				)
				(justify left bottom)
				(hide yes)
			)
		)
		(property "License" "Apache-2.0"
			(at 97.79 161.29 0)
			(effects
				(font
					(size 1.27 1.27)
					(thickness 0.15)
				)
				(justify left bottom)
				(hide yes)
			)
		)
		(pin "1"
		)
		(instances
			(project "thunderbolt-gpu-adapter"
				(path ""
					(reference "#PWR078")
					(unit 1)
				)
			)
		)
	)
	(symbol
		(lib_id "antmicroCapacitorspol:C_Pol_330u_6.3V_KEMET-T520-B")
		(at 101.6 279.4 270)
		(unit 1)
		(exclude_from_sim no)
		(in_bom yes)
		(on_board yes)
		(dnp no)
		(property "Reference" "C143"
			(at 99.06 280.1366 90)
			(effects
				(font
					(size 1.27 1.27)
					(thickness 0.15)
				)
				(justify right)
			)
		)
		(property "Value" "C_Pol_330u_6.3V_KEMET-T520-B"
			(at 99.06 293.37 0)
			(effects
				(font
					(size 1.27 1.27)
					(thickness 0.15)
				)
				(justify left bottom)
				(hide yes)
			)
		)
		(property "Footprint" "antmicro-footprints:C_Pol_EIA-B"
			(at 93.98 293.37 0)
			(effects
				(font
					(size 1.27 1.27)
					(thickness 0.15)
				)
				(justify left bottom)
				(hide yes)
			)
		)
		(property "Datasheet" "https://www.kemet.com/en/us/capacitors/product/T520B337M006ATE040.html"
			(at 91.44 293.37 0)
			(effects
				(font
					(size 1.27 1.27)
					(thickness 0.15)
				)
				(justify left bottom)
				(hide yes)
			)
		)
		(property "Description" ""
			(at 101.6 279.4 0)
			(effects
				(font
					(size 1.27 1.27)
				)
				(hide yes)
			)
		)
		(property "Val" "330u"
			(at 99.06 282.6766 90)
			(effects
				(font
					(size 1.27 1.27)
					(thickness 0.15)
				)
				(justify right)
			)
		)
		(property "MPN" "T520B337M006ATE040"
			(at 88.9 293.37 0)
			(effects
				(font
					(size 1.27 1.27)
					(thickness 0.15)
				)
				(justify left bottom)
				(hide yes)
			)
		)
		(property "Manufacturer" "KEMET"
			(at 86.36 293.37 0)
			(effects
				(font
					(size 1.27 1.27)
					(thickness 0.15)
				)
				(justify left bottom)
				(hide yes)
			)
		)
		(property "License" "Apache-2.0"
			(at 83.82 293.37 0)
			(effects
				(font
					(size 1.27 1.27)
					(thickness 0.15)
				)
				(justify left bottom)
				(hide yes)
			)
		)
		(property "Author" "Antmicro"
			(at 81.28 293.37 0)
			(effects
				(font
					(size 1.27 1.27)
					(thickness 0.15)
				)
				(justify left bottom)
				(hide yes)
			)
		)
		(property "Voltage" "6.3V"
			(at 78.74 293.37 0)
			(effects
				(font
					(size 1.27 1.27)
				)
				(justify left bottom)
				(hide yes)
			)
		)
		(property "Dielectric" "template_dielectric"
			(at 76.2 293.37 0)
			(effects
				(font
					(size 1.27 1.27)
				)
				(justify left bottom)
				(hide yes)
			)
		)
		(pin "1"
		)
		(pin "2"
		)
		(instances
			(project "thunderbolt-gpu-adapter"
				(path ""
					(reference "C143")
					(unit 1)
				)
			)
		)
	)
	(symbol
		(lib_id "antmicropower:GND")
		(at 193.04 134.62 0)
		(unit 1)
		(exclude_from_sim no)
		(in_bom yes)
		(on_board yes)
		(dnp no)
		(property "Reference" "#PWR0121"
			(at 193.04 140.97 0)
			(effects
				(font
					(size 1.27 1.27)
				)
				(hide yes)
			)
		)
		(property "Value" "GND"
			(at 193.04 138.43 0)
			(effects
				(font
					(size 1.27 1.27)
				)
			)
		)
		(property "Footprint" ""
			(at 193.04 134.62 0)
			(effects
				(font
					(size 1.27 1.27)
				)
				(hide yes)
			)
		)
		(property "Datasheet" ""
			(at 193.04 134.62 0)
			(effects
				(font
					(size 1.27 1.27)
				)
				(hide yes)
			)
		)
		(property "Description" ""
			(at 193.04 134.62 0)
			(effects
				(font
					(size 1.27 1.27)
				)
				(hide yes)
			)
		)
		(property "Author" "Antmicro"
			(at 201.93 142.24 0)
			(effects
				(font
					(size 1.27 1.27)
					(thickness 0.15)
				)
				(justify left bottom)
				(hide yes)
			)
		)
		(property "License" "Apache-2.0"
			(at 201.93 144.78 0)
			(effects
				(font
					(size 1.27 1.27)
					(thickness 0.15)
				)
				(justify left bottom)
				(hide yes)
			)
		)
		(pin "1"
		)
		(instances
			(project "thunderbolt-gpu-adapter"
				(path ""
					(reference "#PWR0121")
					(unit 1)
				)
			)
		)
	)
	(symbol
		(lib_id "antmicropower:GND")
		(at 176.53 224.79 0)
		(unit 1)
		(exclude_from_sim no)
		(in_bom yes)
		(on_board yes)
		(dnp no)
		(property "Reference" "#PWR096"
			(at 176.53 231.14 0)
			(effects
				(font
					(size 1.27 1.27)
				)
				(hide yes)
			)
		)
		(property "Value" "GND"
			(at 176.53 228.6 0)
			(effects
				(font
					(size 1.27 1.27)
				)
			)
		)
		(property "Footprint" ""
			(at 176.53 224.79 0)
			(effects
				(font
					(size 1.27 1.27)
				)
				(hide yes)
			)
		)
		(property "Datasheet" ""
			(at 176.53 224.79 0)
			(effects
				(font
					(size 1.27 1.27)
				)
				(hide yes)
			)
		)
		(property "Description" ""
			(at 176.53 224.79 0)
			(effects
				(font
					(size 1.27 1.27)
				)
				(hide yes)
			)
		)
		(property "Author" "Antmicro"
			(at 185.42 232.41 0)
			(effects
				(font
					(size 1.27 1.27)
					(thickness 0.15)
				)
				(justify left bottom)
				(hide yes)
			)
		)
		(property "License" "Apache-2.0"
			(at 185.42 234.95 0)
			(effects
				(font
					(size 1.27 1.27)
					(thickness 0.15)
				)
				(justify left bottom)
				(hide yes)
			)
		)
		(pin "1"
		)
		(instances
			(project "thunderbolt-gpu-adapter"
				(path ""
					(reference "#PWR096")
					(unit 1)
				)
			)
		)
	)
	(symbol
		(lib_id "antmicropower:GND")
		(at 180.34 152.4 0)
		(mirror y)
		(unit 1)
		(exclude_from_sim no)
		(in_bom yes)
		(on_board yes)
		(dnp no)
		(property "Reference" "#PWR0103"
			(at 180.34 158.75 0)
			(effects
				(font
					(size 1.27 1.27)
				)
				(hide yes)
			)
		)
		(property "Value" "GND"
			(at 180.34 156.21 0)
			(effects
				(font
					(size 1.27 1.27)
				)
			)
		)
		(property "Footprint" ""
			(at 180.34 152.4 0)
			(effects
				(font
					(size 1.27 1.27)
				)
				(hide yes)
			)
		)
		(property "Datasheet" ""
			(at 180.34 152.4 0)
			(effects
				(font
					(size 1.27 1.27)
				)
				(hide yes)
			)
		)
		(property "Description" ""
			(at 180.34 152.4 0)
			(effects
				(font
					(size 1.27 1.27)
				)
				(hide yes)
			)
		)
		(property "Author" "Antmicro"
			(at 171.45 160.02 0)
			(effects
				(font
					(size 1.27 1.27)
					(thickness 0.15)
				)
				(justify left bottom)
				(hide yes)
			)
		)
		(property "License" "Apache-2.0"
			(at 171.45 162.56 0)
			(effects
				(font
					(size 1.27 1.27)
					(thickness 0.15)
				)
				(justify left bottom)
				(hide yes)
			)
		)
		(pin "1"
		)
		(instances
			(project "thunderbolt-gpu-adapter"
				(path ""
					(reference "#PWR0103")
					(unit 1)
				)
			)
		)
	)
	(symbol
		(lib_id "antmicroCapacitors0402:C_100n_0402")
		(at 116.84 284.48 90)
		(unit 1)
		(exclude_from_sim no)
		(in_bom yes)
		(on_board yes)
		(dnp no)
		(property "Reference" "C135"
			(at 114.3 280.035 90)
			(effects
				(font
					(size 1.27 1.27)
					(thickness 0.15)
				)
				(justify left)
			)
		)
		(property "Value" "C_100n_0402"
			(at 127 264.16 0)
			(effects
				(font
					(size 1.27 1.27)
					(thickness 0.15)
				)
				(justify left bottom)
				(hide yes)
			)
		)
		(property "Footprint" "antmicro-footprints:C_0402_1005Metric"
			(at 129.54 264.16 0)
			(effects
				(font
					(size 1.27 1.27)
					(thickness 0.15)
				)
				(justify left bottom)
				(hide yes)
			)
		)
		(property "Datasheet" "https://www.murata.com/products/productdetail?partno=GRM155R61H104KE14%23"
			(at 132.08 264.16 0)
			(effects
				(font
					(size 1.27 1.27)
					(thickness 0.15)
				)
				(justify left bottom)
				(hide yes)
			)
		)
		(property "Description" ""
			(at 116.84 284.48 0)
			(effects
				(font
					(size 1.27 1.27)
				)
				(hide yes)
			)
		)
		(property "MPN" "GRM155R61H104KE14D"
			(at 134.62 264.16 0)
			(effects
				(font
					(size 1.27 1.27)
					(thickness 0.15)
				)
				(justify left bottom)
				(hide yes)
			)
		)
		(property "Manufacturer" "Murata"
			(at 137.16 264.16 0)
			(effects
				(font
					(size 1.27 1.27)
					(thickness 0.15)
				)
				(justify left bottom)
				(hide yes)
			)
		)
		(property "License" "Apache-2.0"
			(at 139.7 264.16 0)
			(effects
				(font
					(size 1.27 1.27)
					(thickness 0.15)
				)
				(justify left bottom)
				(hide yes)
			)
		)
		(property "Val" "100n"
			(at 114.3 282.575 90)
			(effects
				(font
					(size 1.27 1.27)
					(thickness 0.15)
				)
				(justify left)
			)
		)
		(property "Voltage" "50V"
			(at 144.78 264.16 0)
			(effects
				(font
					(size 1.27 1.27)
				)
				(justify left bottom)
				(hide yes)
			)
		)
		(property "Dielectric" "X5R"
			(at 147.32 264.16 0)
			(effects
				(font
					(size 1.27 1.27)
				)
				(justify left bottom)
				(hide yes)
			)
		)
		(property "Author" "Antmicro"
			(at 142.24 264.16 0)
			(effects
				(font
					(size 1.27 1.27)
					(thickness 0.15)
				)
				(justify left bottom)
				(hide yes)
			)
		)
		(pin "1"
		)
		(pin "2"
		)
		(instances
			(project "thunderbolt-gpu-adapter"
				(path ""
					(reference "C135")
					(unit 1)
				)
			)
		)
	)
	(symbol
		(lib_id "antmicropower:GND")
		(at 186.69 184.15 0)
		(unit 1)
		(exclude_from_sim no)
		(in_bom yes)
		(on_board yes)
		(dnp no)
		(property "Reference" "#PWR0105"
			(at 186.69 190.5 0)
			(effects
				(font
					(size 1.27 1.27)
				)
				(hide yes)
			)
		)
		(property "Value" "GND"
			(at 186.69 187.96 0)
			(effects
				(font
					(size 1.27 1.27)
				)
			)
		)
		(property "Footprint" ""
			(at 186.69 184.15 0)
			(effects
				(font
					(size 1.27 1.27)
				)
				(hide yes)
			)
		)
		(property "Datasheet" ""
			(at 186.69 184.15 0)
			(effects
				(font
					(size 1.27 1.27)
				)
				(hide yes)
			)
		)
		(property "Description" ""
			(at 186.69 184.15 0)
			(effects
				(font
					(size 1.27 1.27)
				)
				(hide yes)
			)
		)
		(property "Author" "Antmicro"
			(at 195.58 191.77 0)
			(effects
				(font
					(size 1.27 1.27)
					(thickness 0.15)
				)
				(justify left bottom)
				(hide yes)
			)
		)
		(property "License" "Apache-2.0"
			(at 195.58 194.31 0)
			(effects
				(font
					(size 1.27 1.27)
					(thickness 0.15)
				)
				(justify left bottom)
				(hide yes)
			)
		)
		(pin "1"
		)
		(instances
			(project "thunderbolt-gpu-adapter"
				(path ""
					(reference "#PWR0105")
					(unit 1)
				)
			)
		)
	)
	(symbol
		(lib_id "antmicroCapacitors0603:C_22u_0603")
		(at 205.74 201.93 90)
		(unit 1)
		(exclude_from_sim no)
		(in_bom yes)
		(on_board yes)
		(dnp no)
		(property "Reference" "C89"
			(at 206.375 197.485 90)
			(effects
				(font
					(size 1.27 1.27)
					(thickness 0.15)
				)
				(justify right)
			)
		)
		(property "Value" "C_22u_0603"
			(at 215.9 181.61 0)
			(effects
				(font
					(size 1.27 1.27)
					(thickness 0.15)
				)
				(justify left bottom)
				(hide yes)
			)
		)
		(property "Footprint" "antmicro-footprints:C_0603_1608Metric"
			(at 218.44 181.61 0)
			(effects
				(font
					(size 1.27 1.27)
					(thickness 0.15)
				)
				(justify left bottom)
				(hide yes)
			)
		)
		(property "Datasheet" "https://www.murata.com/products/productdetail?partno=GRM188R60J226MEA0%23"
			(at 220.98 181.61 0)
			(effects
				(font
					(size 1.27 1.27)
					(thickness 0.15)
				)
				(justify left bottom)
				(hide yes)
			)
		)
		(property "Description" ""
			(at 205.74 201.93 0)
			(effects
				(font
					(size 1.27 1.27)
				)
				(hide yes)
			)
		)
		(property "MPN" "GRM188R60J226MEA0D"
			(at 223.52 181.61 0)
			(effects
				(font
					(size 1.27 1.27)
					(thickness 0.15)
				)
				(justify left bottom)
				(hide yes)
			)
		)
		(property "Manufacturer" "Murata"
			(at 226.06 181.61 0)
			(effects
				(font
					(size 1.27 1.27)
					(thickness 0.15)
				)
				(justify left bottom)
				(hide yes)
			)
		)
		(property "License" "Apache-2.0"
			(at 228.6 181.61 0)
			(effects
				(font
					(size 1.27 1.27)
					(thickness 0.15)
				)
				(justify left bottom)
				(hide yes)
			)
		)
		(property "Val" "22u"
			(at 206.375 201.295 90)
			(effects
				(font
					(size 1.27 1.27)
					(thickness 0.15)
				)
				(justify right)
			)
		)
		(property "Voltage" ""
			(at 233.68 181.61 0)
			(effects
				(font
					(size 1.27 1.27)
				)
				(justify left bottom)
				(hide yes)
			)
		)
		(property "Dielectric" ""
			(at 236.22 181.61 0)
			(effects
				(font
					(size 1.27 1.27)
				)
				(justify left bottom)
				(hide yes)
			)
		)
		(property "Author" "Antmicro"
			(at 231.14 181.61 0)
			(effects
				(font
					(size 1.27 1.27)
					(thickness 0.15)
				)
				(justify left bottom)
				(hide yes)
			)
		)
		(pin "1"
		)
		(pin "2"
		)
		(instances
			(project "thunderbolt-gpu-adapter"
				(path ""
					(reference "C89")
					(unit 1)
				)
			)
		)
	)
	(symbol
		(lib_id "antmicroCapacitors0402:C_1u_0402")
		(at 186.69 149.86 90)
		(unit 1)
		(exclude_from_sim no)
		(in_bom yes)
		(on_board yes)
		(dnp no)
		(fields_autoplaced yes)
		(property "Reference" "C72"
			(at 189.865 146.0436 90)
			(effects
				(font
					(size 1.27 1.27)
					(thickness 0.15)
				)
				(justify right)
			)
		)
		(property "Value" "C_1u_0402"
			(at 196.85 129.54 0)
			(effects
				(font
					(size 1.27 1.27)
					(thickness 0.15)
				)
				(justify left bottom)
				(hide yes)
			)
		)
		(property "Footprint" "antmicro-footprints:C_0402_1005Metric"
			(at 199.39 129.54 0)
			(effects
				(font
					(size 1.27 1.27)
					(thickness 0.15)
				)
				(justify left bottom)
				(hide yes)
			)
		)
		(property "Datasheet" "https://product.tdk.com/en/search/capacitor/ceramic/mlcc/info?part_no=C1005X6S1A105K050BC"
			(at 201.93 129.54 0)
			(effects
				(font
					(size 1.27 1.27)
					(thickness 0.15)
				)
				(justify left bottom)
				(hide yes)
			)
		)
		(property "Description" ""
			(at 186.69 149.86 0)
			(effects
				(font
					(size 1.27 1.27)
				)
				(hide yes)
			)
		)
		(property "MPN" "C1005X6S1A105K050BC"
			(at 204.47 129.54 0)
			(effects
				(font
					(size 1.27 1.27)
					(thickness 0.15)
				)
				(justify left bottom)
				(hide yes)
			)
		)
		(property "Manufacturer" "TDK"
			(at 207.01 129.54 0)
			(effects
				(font
					(size 1.27 1.27)
					(thickness 0.15)
				)
				(justify left bottom)
				(hide yes)
			)
		)
		(property "License" "Apache-2.0"
			(at 209.55 129.54 0)
			(effects
				(font
					(size 1.27 1.27)
					(thickness 0.15)
				)
				(justify left bottom)
				(hide yes)
			)
		)
		(property "Val" "1u"
			(at 189.865 148.5836 90)
			(effects
				(font
					(size 1.27 1.27)
					(thickness 0.15)
				)
				(justify right)
			)
		)
		(property "Voltage" ""
			(at 214.63 129.54 0)
			(effects
				(font
					(size 1.27 1.27)
				)
				(justify left bottom)
				(hide yes)
			)
		)
		(property "Dielectric" ""
			(at 217.17 129.54 0)
			(effects
				(font
					(size 1.27 1.27)
				)
				(justify left bottom)
				(hide yes)
			)
		)
		(property "Author" "Antmicro"
			(at 212.09 129.54 0)
			(effects
				(font
					(size 1.27 1.27)
					(thickness 0.15)
				)
				(justify left bottom)
				(hide yes)
			)
		)
		(pin "1"
		)
		(pin "2"
		)
		(instances
			(project "thunderbolt-gpu-adapter"
				(path ""
					(reference "C72")
					(unit 1)
				)
			)
		)
	)
	(symbol
		(lib_id "antmicroCapacitors0402:C_1u_0402")
		(at 93.98 166.37 90)
		(unit 1)
		(exclude_from_sim no)
		(in_bom yes)
		(on_board yes)
		(dnp no)
		(property "Reference" "C56"
			(at 94.615 161.925 90)
			(effects
				(font
					(size 1.27 1.27)
					(thickness 0.15)
				)
				(justify right)
			)
		)
		(property "Value" "C_1u_0402"
			(at 104.14 146.05 0)
			(effects
				(font
					(size 1.27 1.27)
					(thickness 0.15)
				)
				(justify left bottom)
				(hide yes)
			)
		)
		(property "Footprint" "antmicro-footprints:C_0402_1005Metric"
			(at 106.68 146.05 0)
			(effects
				(font
					(size 1.27 1.27)
					(thickness 0.15)
				)
				(justify left bottom)
				(hide yes)
			)
		)
		(property "Datasheet" "https://product.tdk.com/en/search/capacitor/ceramic/mlcc/info?part_no=C1005X6S1A105K050BC"
			(at 109.22 146.05 0)
			(effects
				(font
					(size 1.27 1.27)
					(thickness 0.15)
				)
				(justify left bottom)
				(hide yes)
			)
		)
		(property "Description" ""
			(at 93.98 166.37 0)
			(effects
				(font
					(size 1.27 1.27)
				)
				(hide yes)
			)
		)
		(property "MPN" "C1005X6S1A105K050BC"
			(at 111.76 146.05 0)
			(effects
				(font
					(size 1.27 1.27)
					(thickness 0.15)
				)
				(justify left bottom)
				(hide yes)
			)
		)
		(property "Manufacturer" "TDK"
			(at 114.3 146.05 0)
			(effects
				(font
					(size 1.27 1.27)
					(thickness 0.15)
				)
				(justify left bottom)
				(hide yes)
			)
		)
		(property "License" "Apache-2.0"
			(at 116.84 146.05 0)
			(effects
				(font
					(size 1.27 1.27)
					(thickness 0.15)
				)
				(justify left bottom)
				(hide yes)
			)
		)
		(property "Val" "1u"
			(at 94.615 165.735 90)
			(effects
				(font
					(size 1.27 1.27)
					(thickness 0.15)
				)
				(justify right)
			)
		)
		(property "Voltage" ""
			(at 121.92 146.05 0)
			(effects
				(font
					(size 1.27 1.27)
				)
				(justify left bottom)
				(hide yes)
			)
		)
		(property "Dielectric" ""
			(at 124.46 146.05 0)
			(effects
				(font
					(size 1.27 1.27)
				)
				(justify left bottom)
				(hide yes)
			)
		)
		(property "Author" "Antmicro"
			(at 119.38 146.05 0)
			(effects
				(font
					(size 1.27 1.27)
					(thickness 0.15)
				)
				(justify left bottom)
				(hide yes)
			)
		)
		(pin "1"
		)
		(pin "2"
		)
		(instances
			(project "thunderbolt-gpu-adapter"
				(path ""
					(reference "C56")
					(unit 1)
				)
			)
		)
	)
	(symbol
		(lib_id "antmicroCapacitors0402:C_100n_0402")
		(at 186.69 133.35 90)
		(unit 1)
		(exclude_from_sim no)
		(in_bom yes)
		(on_board yes)
		(dnp no)
		(property "Reference" "C91"
			(at 187.325 128.905 90)
			(effects
				(font
					(size 1.27 1.27)
					(thickness 0.15)
				)
				(justify right)
			)
		)
		(property "Value" "C_100n_0402"
			(at 196.85 113.03 0)
			(effects
				(font
					(size 1.27 1.27)
					(thickness 0.15)
				)
				(justify left bottom)
				(hide yes)
			)
		)
		(property "Footprint" "antmicro-footprints:C_0402_1005Metric"
			(at 199.39 113.03 0)
			(effects
				(font
					(size 1.27 1.27)
					(thickness 0.15)
				)
				(justify left bottom)
				(hide yes)
			)
		)
		(property "Datasheet" "https://www.murata.com/products/productdetail?partno=GRM155R61H104KE14%23"
			(at 201.93 113.03 0)
			(effects
				(font
					(size 1.27 1.27)
					(thickness 0.15)
				)
				(justify left bottom)
				(hide yes)
			)
		)
		(property "Description" ""
			(at 186.69 133.35 0)
			(effects
				(font
					(size 1.27 1.27)
				)
				(hide yes)
			)
		)
		(property "MPN" "GRM155R61H104KE14D"
			(at 204.47 113.03 0)
			(effects
				(font
					(size 1.27 1.27)
					(thickness 0.15)
				)
				(justify left bottom)
				(hide yes)
			)
		)
		(property "Manufacturer" "Murata"
			(at 207.01 113.03 0)
			(effects
				(font
					(size 1.27 1.27)
					(thickness 0.15)
				)
				(justify left bottom)
				(hide yes)
			)
		)
		(property "License" "Apache-2.0"
			(at 209.55 113.03 0)
			(effects
				(font
					(size 1.27 1.27)
					(thickness 0.15)
				)
				(justify left bottom)
				(hide yes)
			)
		)
		(property "Val" "100n"
			(at 187.325 132.715 90)
			(effects
				(font
					(size 1.27 1.27)
					(thickness 0.15)
				)
				(justify right)
			)
		)
		(property "Voltage" "50V"
			(at 214.63 113.03 0)
			(effects
				(font
					(size 1.27 1.27)
				)
				(justify left bottom)
				(hide yes)
			)
		)
		(property "Dielectric" "X5R"
			(at 217.17 113.03 0)
			(effects
				(font
					(size 1.27 1.27)
				)
				(justify left bottom)
				(hide yes)
			)
		)
		(property "Author" "Antmicro"
			(at 212.09 113.03 0)
			(effects
				(font
					(size 1.27 1.27)
					(thickness 0.15)
				)
				(justify left bottom)
				(hide yes)
			)
		)
		(pin "1"
		)
		(pin "2"
		)
		(instances
			(project "thunderbolt-gpu-adapter"
				(path ""
					(reference "C91")
					(unit 1)
				)
			)
		)
	)
	(symbol
		(lib_id "antmicroTransistorsBipolarSingle:BC817-25W")
		(at 210.82 281.94 0)
		(unit 1)
		(exclude_from_sim no)
		(in_bom yes)
		(on_board yes)
		(dnp no)
		(fields_autoplaced yes)
		(property "Reference" "Q1"
			(at 219.71 280.67 0)
			(effects
				(font
					(size 1.27 1.27)
					(thickness 0.15)
				)
				(justify left)
			)
		)
		(property "Value" "BC817-25W"
			(at 233.68 284.48 0)
			(effects
				(font
					(size 1.27 1.27)
					(thickness 0.15)
				)
				(justify left bottom)
				(hide yes)
			)
		)
		(property "Footprint" "antmicro-footprints:SOT-323"
			(at 233.68 287.02 0)
			(effects
				(font
					(size 1.27 1.27)
					(thickness 0.15)
				)
				(justify left bottom)
				(hide yes)
			)
		)
		(property "Datasheet" "https://assets.nexperia.com/documents/data-sheet/BC817W_SER.pdf"
			(at 233.68 289.56 0)
			(effects
				(font
					(size 1.27 1.27)
					(thickness 0.15)
				)
				(justify left bottom)
				(hide yes)
			)
		)
		(property "Description" ""
			(at 210.82 281.94 0)
			(effects
				(font
					(size 1.27 1.27)
				)
				(hide yes)
			)
		)
		(property "MPN" "BC817-25W,115"
			(at 219.71 283.21 0)
			(effects
				(font
					(size 1.27 1.27)
					(thickness 0.15)
				)
				(justify left)
			)
		)
		(property "Manufacturer" "Nexperia"
			(at 233.68 294.64 0)
			(effects
				(font
					(size 1.27 1.27)
					(thickness 0.15)
				)
				(justify left bottom)
				(hide yes)
			)
		)
		(property "License" "Apache-2.0"
			(at 233.68 299.72 0)
			(effects
				(font
					(size 1.27 1.27)
					(thickness 0.15)
				)
				(justify left bottom)
				(hide yes)
			)
		)
		(property "Author" "Antmicro"
			(at 233.68 297.18 0)
			(effects
				(font
					(size 1.27 1.27)
					(thickness 0.15)
				)
				(justify left bottom)
				(hide yes)
			)
		)
		(pin "1"
		)
		(pin "2"
		)
		(pin "3"
		)
		(instances
			(project "thunderbolt-gpu-adapter"
				(path ""
					(reference "Q1")
					(unit 1)
				)
			)
		)
	)
	(symbol
		(lib_id "antmicroCapacitors0402:C_1u_0402")
		(at 186.69 182.88 90)
		(unit 1)
		(exclude_from_sim no)
		(in_bom yes)
		(on_board yes)
		(dnp no)
		(property "Reference" "C77"
			(at 187.96 178.435 90)
			(effects
				(font
					(size 1.27 1.27)
					(thickness 0.15)
				)
				(justify right)
			)
		)
		(property "Value" "C_1u_0402"
			(at 196.85 162.56 0)
			(effects
				(font
					(size 1.27 1.27)
					(thickness 0.15)
				)
				(justify left bottom)
				(hide yes)
			)
		)
		(property "Footprint" "antmicro-footprints:C_0402_1005Metric"
			(at 199.39 162.56 0)
			(effects
				(font
					(size 1.27 1.27)
					(thickness 0.15)
				)
				(justify left bottom)
				(hide yes)
			)
		)
		(property "Datasheet" "https://product.tdk.com/en/search/capacitor/ceramic/mlcc/info?part_no=C1005X6S1A105K050BC"
			(at 201.93 162.56 0)
			(effects
				(font
					(size 1.27 1.27)
					(thickness 0.15)
				)
				(justify left bottom)
				(hide yes)
			)
		)
		(property "Description" ""
			(at 186.69 182.88 0)
			(effects
				(font
					(size 1.27 1.27)
				)
				(hide yes)
			)
		)
		(property "MPN" "C1005X6S1A105K050BC"
			(at 204.47 162.56 0)
			(effects
				(font
					(size 1.27 1.27)
					(thickness 0.15)
				)
				(justify left bottom)
				(hide yes)
			)
		)
		(property "Manufacturer" "TDK"
			(at 207.01 162.56 0)
			(effects
				(font
					(size 1.27 1.27)
					(thickness 0.15)
				)
				(justify left bottom)
				(hide yes)
			)
		)
		(property "License" "Apache-2.0"
			(at 209.55 162.56 0)
			(effects
				(font
					(size 1.27 1.27)
					(thickness 0.15)
				)
				(justify left bottom)
				(hide yes)
			)
		)
		(property "Val" "1u"
			(at 187.325 182.245 90)
			(effects
				(font
					(size 1.27 1.27)
					(thickness 0.15)
				)
				(justify right)
			)
		)
		(property "Voltage" ""
			(at 214.63 162.56 0)
			(effects
				(font
					(size 1.27 1.27)
				)
				(justify left bottom)
				(hide yes)
			)
		)
		(property "Dielectric" ""
			(at 217.17 162.56 0)
			(effects
				(font
					(size 1.27 1.27)
				)
				(justify left bottom)
				(hide yes)
			)
		)
		(property "Author" "Antmicro"
			(at 212.09 162.56 0)
			(effects
				(font
					(size 1.27 1.27)
					(thickness 0.15)
				)
				(justify left bottom)
				(hide yes)
			)
		)
		(pin "1"
		)
		(pin "2"
		)
		(instances
			(project "thunderbolt-gpu-adapter"
				(path ""
					(reference "C77")
					(unit 1)
				)
			)
		)
	)
	(symbol
		(lib_id "antmicroCapacitors0402:C_1u_0402")
		(at 105.41 148.59 90)
		(unit 1)
		(exclude_from_sim no)
		(in_bom yes)
		(on_board yes)
		(dnp no)
		(property "Reference" "C61"
			(at 106.045 144.145 90)
			(effects
				(font
					(size 1.27 1.27)
					(thickness 0.15)
				)
				(justify right)
			)
		)
		(property "Value" "C_1u_0402"
			(at 115.57 128.27 0)
			(effects
				(font
					(size 1.27 1.27)
					(thickness 0.15)
				)
				(justify left bottom)
				(hide yes)
			)
		)
		(property "Footprint" "antmicro-footprints:C_0402_1005Metric"
			(at 118.11 128.27 0)
			(effects
				(font
					(size 1.27 1.27)
					(thickness 0.15)
				)
				(justify left bottom)
				(hide yes)
			)
		)
		(property "Datasheet" "https://product.tdk.com/en/search/capacitor/ceramic/mlcc/info?part_no=C1005X6S1A105K050BC"
			(at 120.65 128.27 0)
			(effects
				(font
					(size 1.27 1.27)
					(thickness 0.15)
				)
				(justify left bottom)
				(hide yes)
			)
		)
		(property "Description" ""
			(at 105.41 148.59 0)
			(effects
				(font
					(size 1.27 1.27)
				)
				(hide yes)
			)
		)
		(property "MPN" "C1005X6S1A105K050BC"
			(at 123.19 128.27 0)
			(effects
				(font
					(size 1.27 1.27)
					(thickness 0.15)
				)
				(justify left bottom)
				(hide yes)
			)
		)
		(property "Manufacturer" "TDK"
			(at 125.73 128.27 0)
			(effects
				(font
					(size 1.27 1.27)
					(thickness 0.15)
				)
				(justify left bottom)
				(hide yes)
			)
		)
		(property "License" "Apache-2.0"
			(at 128.27 128.27 0)
			(effects
				(font
					(size 1.27 1.27)
					(thickness 0.15)
				)
				(justify left bottom)
				(hide yes)
			)
		)
		(property "Val" "1u"
			(at 106.045 147.955 90)
			(effects
				(font
					(size 1.27 1.27)
					(thickness 0.15)
				)
				(justify right)
			)
		)
		(property "Voltage" ""
			(at 133.35 128.27 0)
			(effects
				(font
					(size 1.27 1.27)
				)
				(justify left bottom)
				(hide yes)
			)
		)
		(property "Dielectric" ""
			(at 135.89 128.27 0)
			(effects
				(font
					(size 1.27 1.27)
				)
				(justify left bottom)
				(hide yes)
			)
		)
		(property "Author" "Antmicro"
			(at 130.81 128.27 0)
			(effects
				(font
					(size 1.27 1.27)
					(thickness 0.15)
				)
				(justify left bottom)
				(hide yes)
			)
		)
		(pin "1"
		)
		(pin "2"
		)
		(instances
			(project "thunderbolt-gpu-adapter"
				(path ""
					(reference "C61")
					(unit 1)
				)
			)
		)
	)
	(symbol
		(lib_id "antmicroCapacitors0402:C_1u_0402")
		(at 93.98 148.59 90)
		(unit 1)
		(exclude_from_sim no)
		(in_bom yes)
		(on_board yes)
		(dnp no)
		(property "Reference" "C55"
			(at 94.615 144.145 90)
			(effects
				(font
					(size 1.27 1.27)
					(thickness 0.15)
				)
				(justify right)
			)
		)
		(property "Value" "C_1u_0402"
			(at 104.14 128.27 0)
			(effects
				(font
					(size 1.27 1.27)
					(thickness 0.15)
				)
				(justify left bottom)
				(hide yes)
			)
		)
		(property "Footprint" "antmicro-footprints:C_0402_1005Metric"
			(at 106.68 128.27 0)
			(effects
				(font
					(size 1.27 1.27)
					(thickness 0.15)
				)
				(justify left bottom)
				(hide yes)
			)
		)
		(property "Datasheet" "https://product.tdk.com/en/search/capacitor/ceramic/mlcc/info?part_no=C1005X6S1A105K050BC"
			(at 109.22 128.27 0)
			(effects
				(font
					(size 1.27 1.27)
					(thickness 0.15)
				)
				(justify left bottom)
				(hide yes)
			)
		)
		(property "Description" ""
			(at 93.98 148.59 0)
			(effects
				(font
					(size 1.27 1.27)
				)
				(hide yes)
			)
		)
		(property "MPN" "C1005X6S1A105K050BC"
			(at 111.76 128.27 0)
			(effects
				(font
					(size 1.27 1.27)
					(thickness 0.15)
				)
				(justify left bottom)
				(hide yes)
			)
		)
		(property "Manufacturer" "TDK"
			(at 114.3 128.27 0)
			(effects
				(font
					(size 1.27 1.27)
					(thickness 0.15)
				)
				(justify left bottom)
				(hide yes)
			)
		)
		(property "License" "Apache-2.0"
			(at 116.84 128.27 0)
			(effects
				(font
					(size 1.27 1.27)
					(thickness 0.15)
				)
				(justify left bottom)
				(hide yes)
			)
		)
		(property "Val" "1u"
			(at 94.615 147.955 90)
			(effects
				(font
					(size 1.27 1.27)
					(thickness 0.15)
				)
				(justify right)
			)
		)
		(property "Voltage" ""
			(at 121.92 128.27 0)
			(effects
				(font
					(size 1.27 1.27)
				)
				(justify left bottom)
				(hide yes)
			)
		)
		(property "Dielectric" ""
			(at 124.46 128.27 0)
			(effects
				(font
					(size 1.27 1.27)
				)
				(justify left bottom)
				(hide yes)
			)
		)
		(property "Author" "Antmicro"
			(at 119.38 128.27 0)
			(effects
				(font
					(size 1.27 1.27)
					(thickness 0.15)
				)
				(justify left bottom)
				(hide yes)
			)
		)
		(pin "1"
		)
		(pin "2"
		)
		(instances
			(project "thunderbolt-gpu-adapter"
				(path ""
					(reference "C55")
					(unit 1)
				)
			)
		)
	)
	(symbol
		(lib_id "antmicroCapacitors0402:C_10u_0402")
		(at 224.79 133.35 90)
		(unit 1)
		(exclude_from_sim no)
		(in_bom yes)
		(on_board yes)
		(dnp no)
		(property "Reference" "C76"
			(at 225.425 128.905 90)
			(effects
				(font
					(size 1.27 1.27)
					(thickness 0.15)
				)
				(justify right)
			)
		)
		(property "Value" "C_10u_0402"
			(at 234.95 113.03 0)
			(effects
				(font
					(size 1.27 1.27)
					(thickness 0.15)
				)
				(justify left bottom)
				(hide yes)
			)
		)
		(property "Footprint" "antmicro-footprints:C_0402_1005Metric"
			(at 237.49 113.03 0)
			(effects
				(font
					(size 1.27 1.27)
					(thickness 0.15)
				)
				(justify left bottom)
				(hide yes)
			)
		)
		(property "Datasheet" "https://www.yageo.com/en/Chart/Download/pdf/CC0402MRX5R5BB106"
			(at 240.03 113.03 0)
			(effects
				(font
					(size 1.27 1.27)
					(thickness 0.15)
				)
				(justify left bottom)
				(hide yes)
			)
		)
		(property "Description" ""
			(at 224.79 133.35 0)
			(effects
				(font
					(size 1.27 1.27)
				)
				(hide yes)
			)
		)
		(property "MPN" "CC0402MRX5R5BB106"
			(at 242.57 113.03 0)
			(effects
				(font
					(size 1.27 1.27)
					(thickness 0.15)
				)
				(justify left bottom)
				(hide yes)
			)
		)
		(property "Manufacturer" "YAGEO"
			(at 245.11 113.03 0)
			(effects
				(font
					(size 1.27 1.27)
					(thickness 0.15)
				)
				(justify left bottom)
				(hide yes)
			)
		)
		(property "License" "Apache-2.0"
			(at 247.65 113.03 0)
			(effects
				(font
					(size 1.27 1.27)
					(thickness 0.15)
				)
				(justify left bottom)
				(hide yes)
			)
		)
		(property "Val" "10u"
			(at 225.425 132.715 90)
			(effects
				(font
					(size 1.27 1.27)
					(thickness 0.15)
				)
				(justify right)
			)
		)
		(property "Voltage" ""
			(at 252.73 113.03 0)
			(effects
				(font
					(size 1.27 1.27)
				)
				(justify left bottom)
				(hide yes)
			)
		)
		(property "Dielectric" ""
			(at 255.27 113.03 0)
			(effects
				(font
					(size 1.27 1.27)
				)
				(justify left bottom)
				(hide yes)
			)
		)
		(property "Author" "Antmicro"
			(at 250.19 113.03 0)
			(effects
				(font
					(size 1.27 1.27)
					(thickness 0.15)
				)
				(justify left bottom)
				(hide yes)
			)
		)
		(pin "1"
		)
		(pin "2"
		)
		(instances
			(project "thunderbolt-gpu-adapter"
				(path ""
					(reference "C76")
					(unit 1)
				)
			)
		)
	)
	(symbol
		(lib_id "antmicroResistors0402:R_330R_0402")
		(at 217.17 274.32 90)
		(unit 1)
		(exclude_from_sim no)
		(in_bom yes)
		(on_board yes)
		(dnp no)
		(fields_autoplaced yes)
		(property "Reference" "R49"
			(at 219.71 270.5099 90)
			(effects
				(font
					(size 1.27 1.27)
					(thickness 0.15)
				)
				(justify right)
			)
		)
		(property "Value" "R_330R_0402"
			(at 229.87 254 0)
			(effects
				(font
					(size 1.27 1.27)
					(thickness 0.15)
				)
				(justify left bottom)
				(hide yes)
			)
		)
		(property "Footprint" "antmicro-footprints:R_0402_1005Metric"
			(at 232.41 254 0)
			(effects
				(font
					(size 1.27 1.27)
					(thickness 0.15)
				)
				(justify left bottom)
				(hide yes)
			)
		)
		(property "Datasheet" "https://www.bourns.com/docs/product-datasheets/cr.pdf"
			(at 234.95 254 0)
			(effects
				(font
					(size 1.27 1.27)
					(thickness 0.15)
				)
				(justify left bottom)
				(hide yes)
			)
		)
		(property "Description" ""
			(at 217.17 274.32 0)
			(effects
				(font
					(size 1.27 1.27)
				)
				(hide yes)
			)
		)
		(property "MPN" "CR0402-FX-3300GLF"
			(at 237.49 254 0)
			(effects
				(font
					(size 1.27 1.27)
					(thickness 0.15)
				)
				(justify left bottom)
				(hide yes)
			)
		)
		(property "Manufacturer" "Bourns"
			(at 240.03 254 0)
			(effects
				(font
					(size 1.27 1.27)
					(thickness 0.15)
				)
				(justify left bottom)
				(hide yes)
			)
		)
		(property "License" "Apache-2.0"
			(at 242.57 254 0)
			(effects
				(font
					(size 1.27 1.27)
					(thickness 0.15)
				)
				(justify left bottom)
				(hide yes)
			)
		)
		(property "Val" "330R"
			(at 219.71 273.0499 90)
			(effects
				(font
					(size 1.27 1.27)
					(thickness 0.15)
				)
				(justify right)
			)
		)
		(property "Tolerance" "1%"
			(at 227.33 254 0)
			(effects
				(font
					(size 1.27 1.27)
				)
				(justify left bottom)
				(hide yes)
			)
		)
		(property "Author" "Antmicro"
			(at 245.11 254 0)
			(effects
				(font
					(size 1.27 1.27)
					(thickness 0.15)
				)
				(justify left bottom)
				(hide yes)
			)
		)
		(pin "1"
		)
		(pin "2"
		)
		(instances
			(project "thunderbolt-gpu-adapter"
				(path ""
					(reference "R49")
					(unit 1)
				)
			)
		)
	)
	(symbol
		(lib_id "antmicroCapacitors0402:C_1u_0402")
		(at 111.76 222.25 90)
		(unit 1)
		(exclude_from_sim no)
		(in_bom yes)
		(on_board yes)
		(dnp no)
		(fields_autoplaced yes)
		(property "Reference" "C66"
			(at 109.22 218.4336 90)
			(effects
				(font
					(size 1.27 1.27)
					(thickness 0.15)
				)
				(justify left)
			)
		)
		(property "Value" "C_1u_0402"
			(at 121.92 201.93 0)
			(effects
				(font
					(size 1.27 1.27)
					(thickness 0.15)
				)
				(justify left bottom)
				(hide yes)
			)
		)
		(property "Footprint" "antmicro-footprints:C_0402_1005Metric"
			(at 124.46 201.93 0)
			(effects
				(font
					(size 1.27 1.27)
					(thickness 0.15)
				)
				(justify left bottom)
				(hide yes)
			)
		)
		(property "Datasheet" "https://product.tdk.com/en/search/capacitor/ceramic/mlcc/info?part_no=C1005X6S1A105K050BC"
			(at 127 201.93 0)
			(effects
				(font
					(size 1.27 1.27)
					(thickness 0.15)
				)
				(justify left bottom)
				(hide yes)
			)
		)
		(property "Description" ""
			(at 111.76 222.25 0)
			(effects
				(font
					(size 1.27 1.27)
				)
				(hide yes)
			)
		)
		(property "MPN" "C1005X6S1A105K050BC"
			(at 129.54 201.93 0)
			(effects
				(font
					(size 1.27 1.27)
					(thickness 0.15)
				)
				(justify left bottom)
				(hide yes)
			)
		)
		(property "Manufacturer" "TDK"
			(at 132.08 201.93 0)
			(effects
				(font
					(size 1.27 1.27)
					(thickness 0.15)
				)
				(justify left bottom)
				(hide yes)
			)
		)
		(property "License" "Apache-2.0"
			(at 134.62 201.93 0)
			(effects
				(font
					(size 1.27 1.27)
					(thickness 0.15)
				)
				(justify left bottom)
				(hide yes)
			)
		)
		(property "Val" "1u"
			(at 109.22 220.9736 90)
			(effects
				(font
					(size 1.27 1.27)
					(thickness 0.15)
				)
				(justify left)
			)
		)
		(property "Voltage" ""
			(at 139.7 201.93 0)
			(effects
				(font
					(size 1.27 1.27)
				)
				(justify left bottom)
				(hide yes)
			)
		)
		(property "Dielectric" ""
			(at 142.24 201.93 0)
			(effects
				(font
					(size 1.27 1.27)
				)
				(justify left bottom)
				(hide yes)
			)
		)
		(property "Author" "Antmicro"
			(at 137.16 201.93 0)
			(effects
				(font
					(size 1.27 1.27)
					(thickness 0.15)
				)
				(justify left bottom)
				(hide yes)
			)
		)
		(pin "1"
		)
		(pin "2"
		)
		(instances
			(project "thunderbolt-gpu-adapter"
				(path ""
					(reference "C66")
					(unit 1)
				)
			)
		)
	)
	(symbol
		(lib_id "antmicropower:GND")
		(at 100.33 203.2 0)
		(unit 1)
		(exclude_from_sim no)
		(in_bom yes)
		(on_board yes)
		(dnp no)
		(property "Reference" "#PWR079"
			(at 100.33 209.55 0)
			(effects
				(font
					(size 1.27 1.27)
				)
				(hide yes)
			)
		)
		(property "Value" "GND"
			(at 100.33 207.01 0)
			(effects
				(font
					(size 1.27 1.27)
				)
			)
		)
		(property "Footprint" ""
			(at 100.33 203.2 0)
			(effects
				(font
					(size 1.27 1.27)
				)
				(hide yes)
			)
		)
		(property "Datasheet" ""
			(at 100.33 203.2 0)
			(effects
				(font
					(size 1.27 1.27)
				)
				(hide yes)
			)
		)
		(property "Description" ""
			(at 100.33 203.2 0)
			(effects
				(font
					(size 1.27 1.27)
				)
				(hide yes)
			)
		)
		(property "Author" "Antmicro"
			(at 109.22 210.82 0)
			(effects
				(font
					(size 1.27 1.27)
					(thickness 0.15)
				)
				(justify left bottom)
				(hide yes)
			)
		)
		(property "License" "Apache-2.0"
			(at 109.22 213.36 0)
			(effects
				(font
					(size 1.27 1.27)
					(thickness 0.15)
				)
				(justify left bottom)
				(hide yes)
			)
		)
		(pin "1"
		)
		(instances
			(project "thunderbolt-gpu-adapter"
				(path ""
					(reference "#PWR079")
					(unit 1)
				)
			)
		)
	)
	(symbol
		(lib_id "antmicropower:GND")
		(at 217.17 223.52 0)
		(unit 1)
		(exclude_from_sim no)
		(in_bom yes)
		(on_board yes)
		(dnp no)
		(property "Reference" "#PWR0203"
			(at 217.17 229.87 0)
			(effects
				(font
					(size 1.27 1.27)
				)
				(hide yes)
			)
		)
		(property "Value" "GND"
			(at 217.17 227.33 0)
			(effects
				(font
					(size 1.27 1.27)
				)
			)
		)
		(property "Footprint" ""
			(at 217.17 223.52 0)
			(effects
				(font
					(size 1.27 1.27)
				)
				(hide yes)
			)
		)
		(property "Datasheet" ""
			(at 217.17 223.52 0)
			(effects
				(font
					(size 1.27 1.27)
				)
				(hide yes)
			)
		)
		(property "Description" ""
			(at 217.17 223.52 0)
			(effects
				(font
					(size 1.27 1.27)
				)
				(hide yes)
			)
		)
		(property "Author" "Antmicro"
			(at 226.06 231.14 0)
			(effects
				(font
					(size 1.27 1.27)
					(thickness 0.15)
				)
				(justify left bottom)
				(hide yes)
			)
		)
		(property "License" "Apache-2.0"
			(at 226.06 233.68 0)
			(effects
				(font
					(size 1.27 1.27)
					(thickness 0.15)
				)
				(justify left bottom)
				(hide yes)
			)
		)
		(pin "1"
		)
		(instances
			(project "thunderbolt-gpu-adapter"
				(path ""
					(reference "#PWR0203")
					(unit 1)
				)
			)
		)
	)
	(symbol
		(lib_id "antmicropower:GND")
		(at 180.34 134.62 0)
		(unit 1)
		(exclude_from_sim no)
		(in_bom yes)
		(on_board yes)
		(dnp no)
		(property "Reference" "#PWR0116"
			(at 180.34 140.97 0)
			(effects
				(font
					(size 1.27 1.27)
				)
				(hide yes)
			)
		)
		(property "Value" "GND"
			(at 180.34 138.43 0)
			(effects
				(font
					(size 1.27 1.27)
				)
			)
		)
		(property "Footprint" ""
			(at 180.34 134.62 0)
			(effects
				(font
					(size 1.27 1.27)
				)
				(hide yes)
			)
		)
		(property "Datasheet" ""
			(at 180.34 134.62 0)
			(effects
				(font
					(size 1.27 1.27)
				)
				(hide yes)
			)
		)
		(property "Description" ""
			(at 180.34 134.62 0)
			(effects
				(font
					(size 1.27 1.27)
				)
				(hide yes)
			)
		)
		(property "Author" "Antmicro"
			(at 189.23 142.24 0)
			(effects
				(font
					(size 1.27 1.27)
					(thickness 0.15)
				)
				(justify left bottom)
				(hide yes)
			)
		)
		(property "License" "Apache-2.0"
			(at 189.23 144.78 0)
			(effects
				(font
					(size 1.27 1.27)
					(thickness 0.15)
				)
				(justify left bottom)
				(hide yes)
			)
		)
		(pin "1"
		)
		(instances
			(project "thunderbolt-gpu-adapter"
				(path ""
					(reference "#PWR0116")
					(unit 1)
				)
			)
		)
	)
	(symbol
		(lib_id "antmicroCapacitors0402:C_100n_0402")
		(at 199.39 133.35 90)
		(unit 1)
		(exclude_from_sim no)
		(in_bom yes)
		(on_board yes)
		(dnp no)
		(property "Reference" "C95"
			(at 200.025 128.905 90)
			(effects
				(font
					(size 1.27 1.27)
					(thickness 0.15)
				)
				(justify right)
			)
		)
		(property "Value" "C_100n_0402"
			(at 209.55 113.03 0)
			(effects
				(font
					(size 1.27 1.27)
					(thickness 0.15)
				)
				(justify left bottom)
				(hide yes)
			)
		)
		(property "Footprint" "antmicro-footprints:C_0402_1005Metric"
			(at 212.09 113.03 0)
			(effects
				(font
					(size 1.27 1.27)
					(thickness 0.15)
				)
				(justify left bottom)
				(hide yes)
			)
		)
		(property "Datasheet" "https://www.murata.com/products/productdetail?partno=GRM155R61H104KE14%23"
			(at 214.63 113.03 0)
			(effects
				(font
					(size 1.27 1.27)
					(thickness 0.15)
				)
				(justify left bottom)
				(hide yes)
			)
		)
		(property "Description" ""
			(at 199.39 133.35 0)
			(effects
				(font
					(size 1.27 1.27)
				)
				(hide yes)
			)
		)
		(property "MPN" "GRM155R61H104KE14D"
			(at 217.17 113.03 0)
			(effects
				(font
					(size 1.27 1.27)
					(thickness 0.15)
				)
				(justify left bottom)
				(hide yes)
			)
		)
		(property "Manufacturer" "Murata"
			(at 219.71 113.03 0)
			(effects
				(font
					(size 1.27 1.27)
					(thickness 0.15)
				)
				(justify left bottom)
				(hide yes)
			)
		)
		(property "License" "Apache-2.0"
			(at 222.25 113.03 0)
			(effects
				(font
					(size 1.27 1.27)
					(thickness 0.15)
				)
				(justify left bottom)
				(hide yes)
			)
		)
		(property "Val" "100n"
			(at 200.025 132.715 90)
			(effects
				(font
					(size 1.27 1.27)
					(thickness 0.15)
				)
				(justify right)
			)
		)
		(property "Voltage" "50V"
			(at 227.33 113.03 0)
			(effects
				(font
					(size 1.27 1.27)
				)
				(justify left bottom)
				(hide yes)
			)
		)
		(property "Dielectric" "X5R"
			(at 229.87 113.03 0)
			(effects
				(font
					(size 1.27 1.27)
				)
				(justify left bottom)
				(hide yes)
			)
		)
		(property "Author" "Antmicro"
			(at 224.79 113.03 0)
			(effects
				(font
					(size 1.27 1.27)
					(thickness 0.15)
				)
				(justify left bottom)
				(hide yes)
			)
		)
		(pin "1"
		)
		(pin "2"
		)
		(instances
			(project "thunderbolt-gpu-adapter"
				(path ""
					(reference "C95")
					(unit 1)
				)
			)
		)
	)
	(symbol
		(lib_id "antmicropower:GND")
		(at 111.76 186.69 0)
		(unit 1)
		(exclude_from_sim no)
		(in_bom yes)
		(on_board yes)
		(dnp no)
		(property "Reference" "#PWR076"
			(at 111.76 193.04 0)
			(effects
				(font
					(size 1.27 1.27)
				)
				(hide yes)
			)
		)
		(property "Value" "GND"
			(at 111.76 190.5 0)
			(effects
				(font
					(size 1.27 1.27)
				)
			)
		)
		(property "Footprint" ""
			(at 111.76 186.69 0)
			(effects
				(font
					(size 1.27 1.27)
				)
				(hide yes)
			)
		)
		(property "Datasheet" ""
			(at 111.76 186.69 0)
			(effects
				(font
					(size 1.27 1.27)
				)
				(hide yes)
			)
		)
		(property "Description" ""
			(at 111.76 186.69 0)
			(effects
				(font
					(size 1.27 1.27)
				)
				(hide yes)
			)
		)
		(property "Author" "Antmicro"
			(at 120.65 194.31 0)
			(effects
				(font
					(size 1.27 1.27)
					(thickness 0.15)
				)
				(justify left bottom)
				(hide yes)
			)
		)
		(property "License" "Apache-2.0"
			(at 120.65 196.85 0)
			(effects
				(font
					(size 1.27 1.27)
					(thickness 0.15)
				)
				(justify left bottom)
				(hide yes)
			)
		)
		(pin "1"
		)
		(instances
			(project "thunderbolt-gpu-adapter"
				(path ""
					(reference "#PWR076")
					(unit 1)
				)
			)
		)
	)
	(symbol
		(lib_id "antmicroCapacitors0402:C_1u_0402")
		(at 116.84 166.37 90)
		(unit 1)
		(exclude_from_sim no)
		(in_bom yes)
		(on_board yes)
		(dnp no)
		(property "Reference" "C68"
			(at 117.475 161.925 90)
			(effects
				(font
					(size 1.27 1.27)
					(thickness 0.15)
				)
				(justify right)
			)
		)
		(property "Value" "C_1u_0402"
			(at 127 146.05 0)
			(effects
				(font
					(size 1.27 1.27)
					(thickness 0.15)
				)
				(justify left bottom)
				(hide yes)
			)
		)
		(property "Footprint" "antmicro-footprints:C_0402_1005Metric"
			(at 129.54 146.05 0)
			(effects
				(font
					(size 1.27 1.27)
					(thickness 0.15)
				)
				(justify left bottom)
				(hide yes)
			)
		)
		(property "Datasheet" "https://product.tdk.com/en/search/capacitor/ceramic/mlcc/info?part_no=C1005X6S1A105K050BC"
			(at 132.08 146.05 0)
			(effects
				(font
					(size 1.27 1.27)
					(thickness 0.15)
				)
				(justify left bottom)
				(hide yes)
			)
		)
		(property "Description" ""
			(at 116.84 166.37 0)
			(effects
				(font
					(size 1.27 1.27)
				)
				(hide yes)
			)
		)
		(property "MPN" "C1005X6S1A105K050BC"
			(at 134.62 146.05 0)
			(effects
				(font
					(size 1.27 1.27)
					(thickness 0.15)
				)
				(justify left bottom)
				(hide yes)
			)
		)
		(property "Manufacturer" "TDK"
			(at 137.16 146.05 0)
			(effects
				(font
					(size 1.27 1.27)
					(thickness 0.15)
				)
				(justify left bottom)
				(hide yes)
			)
		)
		(property "License" "Apache-2.0"
			(at 139.7 146.05 0)
			(effects
				(font
					(size 1.27 1.27)
					(thickness 0.15)
				)
				(justify left bottom)
				(hide yes)
			)
		)
		(property "Val" "1u"
			(at 117.475 165.735 90)
			(effects
				(font
					(size 1.27 1.27)
					(thickness 0.15)
				)
				(justify right)
			)
		)
		(property "Voltage" ""
			(at 144.78 146.05 0)
			(effects
				(font
					(size 1.27 1.27)
				)
				(justify left bottom)
				(hide yes)
			)
		)
		(property "Dielectric" ""
			(at 147.32 146.05 0)
			(effects
				(font
					(size 1.27 1.27)
				)
				(justify left bottom)
				(hide yes)
			)
		)
		(property "Author" "Antmicro"
			(at 142.24 146.05 0)
			(effects
				(font
					(size 1.27 1.27)
					(thickness 0.15)
				)
				(justify left bottom)
				(hide yes)
			)
		)
		(pin "1"
		)
		(pin "2"
		)
		(instances
			(project "thunderbolt-gpu-adapter"
				(path ""
					(reference "C68")
					(unit 1)
				)
			)
		)
	)
	(symbol
		(lib_id "antmicropower:GND")
		(at 193.04 167.64 0)
		(unit 1)
		(exclude_from_sim no)
		(in_bom yes)
		(on_board yes)
		(dnp no)
		(property "Reference" "#PWR0122"
			(at 193.04 173.99 0)
			(effects
				(font
					(size 1.27 1.27)
				)
				(hide yes)
			)
		)
		(property "Value" "GND"
			(at 193.04 171.45 0)
			(effects
				(font
					(size 1.27 1.27)
				)
			)
		)
		(property "Footprint" ""
			(at 193.04 167.64 0)
			(effects
				(font
					(size 1.27 1.27)
				)
				(hide yes)
			)
		)
		(property "Datasheet" ""
			(at 193.04 167.64 0)
			(effects
				(font
					(size 1.27 1.27)
				)
				(hide yes)
			)
		)
		(property "Description" ""
			(at 193.04 167.64 0)
			(effects
				(font
					(size 1.27 1.27)
				)
				(hide yes)
			)
		)
		(property "Author" "Antmicro"
			(at 201.93 175.26 0)
			(effects
				(font
					(size 1.27 1.27)
					(thickness 0.15)
				)
				(justify left bottom)
				(hide yes)
			)
		)
		(property "License" "Apache-2.0"
			(at 201.93 177.8 0)
			(effects
				(font
					(size 1.27 1.27)
					(thickness 0.15)
				)
				(justify left bottom)
				(hide yes)
			)
		)
		(pin "1"
		)
		(instances
			(project "thunderbolt-gpu-adapter"
				(path ""
					(reference "#PWR0122")
					(unit 1)
				)
			)
		)
	)
	(symbol
		(lib_id "antmicroCapacitors0402:C_1u_0402")
		(at 105.41 201.93 90)
		(unit 1)
		(exclude_from_sim no)
		(in_bom yes)
		(on_board yes)
		(dnp no)
		(property "Reference" "C57"
			(at 106.045 197.485 90)
			(effects
				(font
					(size 1.27 1.27)
					(thickness 0.15)
				)
				(justify right)
			)
		)
		(property "Value" "C_1u_0402"
			(at 115.57 181.61 0)
			(effects
				(font
					(size 1.27 1.27)
					(thickness 0.15)
				)
				(justify left bottom)
				(hide yes)
			)
		)
		(property "Footprint" "antmicro-footprints:C_0402_1005Metric"
			(at 118.11 181.61 0)
			(effects
				(font
					(size 1.27 1.27)
					(thickness 0.15)
				)
				(justify left bottom)
				(hide yes)
			)
		)
		(property "Datasheet" "https://product.tdk.com/en/search/capacitor/ceramic/mlcc/info?part_no=C1005X6S1A105K050BC"
			(at 120.65 181.61 0)
			(effects
				(font
					(size 1.27 1.27)
					(thickness 0.15)
				)
				(justify left bottom)
				(hide yes)
			)
		)
		(property "Description" ""
			(at 105.41 201.93 0)
			(effects
				(font
					(size 1.27 1.27)
				)
				(hide yes)
			)
		)
		(property "MPN" "C1005X6S1A105K050BC"
			(at 123.19 181.61 0)
			(effects
				(font
					(size 1.27 1.27)
					(thickness 0.15)
				)
				(justify left bottom)
				(hide yes)
			)
		)
		(property "Manufacturer" "TDK"
			(at 125.73 181.61 0)
			(effects
				(font
					(size 1.27 1.27)
					(thickness 0.15)
				)
				(justify left bottom)
				(hide yes)
			)
		)
		(property "License" "Apache-2.0"
			(at 128.27 181.61 0)
			(effects
				(font
					(size 1.27 1.27)
					(thickness 0.15)
				)
				(justify left bottom)
				(hide yes)
			)
		)
		(property "Val" "1u"
			(at 106.045 201.295 90)
			(effects
				(font
					(size 1.27 1.27)
					(thickness 0.15)
				)
				(justify right)
			)
		)
		(property "Voltage" ""
			(at 133.35 181.61 0)
			(effects
				(font
					(size 1.27 1.27)
				)
				(justify left bottom)
				(hide yes)
			)
		)
		(property "Dielectric" ""
			(at 135.89 181.61 0)
			(effects
				(font
					(size 1.27 1.27)
				)
				(justify left bottom)
				(hide yes)
			)
		)
		(property "Author" "Antmicro"
			(at 130.81 181.61 0)
			(effects
				(font
					(size 1.27 1.27)
					(thickness 0.15)
				)
				(justify left bottom)
				(hide yes)
			)
		)
		(pin "1"
		)
		(pin "2"
		)
		(instances
			(project "thunderbolt-gpu-adapter"
				(path ""
					(reference "C57")
					(unit 1)
				)
			)
		)
	)
	(symbol
		(lib_id "antmicropower:GND")
		(at 212.09 167.64 0)
		(unit 1)
		(exclude_from_sim no)
		(in_bom yes)
		(on_board yes)
		(dnp no)
		(property "Reference" "#PWR0127"
			(at 212.09 173.99 0)
			(effects
				(font
					(size 1.27 1.27)
				)
				(hide yes)
			)
		)
		(property "Value" "GND"
			(at 212.09 171.45 0)
			(effects
				(font
					(size 1.27 1.27)
				)
			)
		)
		(property "Footprint" ""
			(at 212.09 167.64 0)
			(effects
				(font
					(size 1.27 1.27)
				)
				(hide yes)
			)
		)
		(property "Datasheet" ""
			(at 212.09 167.64 0)
			(effects
				(font
					(size 1.27 1.27)
				)
				(hide yes)
			)
		)
		(property "Description" ""
			(at 212.09 167.64 0)
			(effects
				(font
					(size 1.27 1.27)
				)
				(hide yes)
			)
		)
		(property "Author" "Antmicro"
			(at 220.98 175.26 0)
			(effects
				(font
					(size 1.27 1.27)
					(thickness 0.15)
				)
				(justify left bottom)
				(hide yes)
			)
		)
		(property "License" "Apache-2.0"
			(at 220.98 177.8 0)
			(effects
				(font
					(size 1.27 1.27)
					(thickness 0.15)
				)
				(justify left bottom)
				(hide yes)
			)
		)
		(pin "1"
		)
		(instances
			(project "thunderbolt-gpu-adapter"
				(path ""
					(reference "#PWR0127")
					(unit 1)
				)
			)
		)
	)
	(symbol
		(lib_id "antmicroCapacitors0402:C_10u_0402")
		(at 231.14 133.35 90)
		(unit 1)
		(exclude_from_sim no)
		(in_bom yes)
		(on_board yes)
		(dnp no)
		(property "Reference" "C80"
			(at 231.775 128.905 90)
			(effects
				(font
					(size 1.27 1.27)
					(thickness 0.15)
				)
				(justify right)
			)
		)
		(property "Value" "C_10u_0402"
			(at 241.3 113.03 0)
			(effects
				(font
					(size 1.27 1.27)
					(thickness 0.15)
				)
				(justify left bottom)
				(hide yes)
			)
		)
		(property "Footprint" "antmicro-footprints:C_0402_1005Metric"
			(at 243.84 113.03 0)
			(effects
				(font
					(size 1.27 1.27)
					(thickness 0.15)
				)
				(justify left bottom)
				(hide yes)
			)
		)
		(property "Datasheet" "https://www.yageo.com/en/Chart/Download/pdf/CC0402MRX5R5BB106"
			(at 246.38 113.03 0)
			(effects
				(font
					(size 1.27 1.27)
					(thickness 0.15)
				)
				(justify left bottom)
				(hide yes)
			)
		)
		(property "Description" ""
			(at 231.14 133.35 0)
			(effects
				(font
					(size 1.27 1.27)
				)
				(hide yes)
			)
		)
		(property "MPN" "CC0402MRX5R5BB106"
			(at 248.92 113.03 0)
			(effects
				(font
					(size 1.27 1.27)
					(thickness 0.15)
				)
				(justify left bottom)
				(hide yes)
			)
		)
		(property "Manufacturer" "YAGEO"
			(at 251.46 113.03 0)
			(effects
				(font
					(size 1.27 1.27)
					(thickness 0.15)
				)
				(justify left bottom)
				(hide yes)
			)
		)
		(property "License" "Apache-2.0"
			(at 254 113.03 0)
			(effects
				(font
					(size 1.27 1.27)
					(thickness 0.15)
				)
				(justify left bottom)
				(hide yes)
			)
		)
		(property "Val" "10u"
			(at 231.775 132.715 90)
			(effects
				(font
					(size 1.27 1.27)
					(thickness 0.15)
				)
				(justify right)
			)
		)
		(property "Voltage" ""
			(at 259.08 113.03 0)
			(effects
				(font
					(size 1.27 1.27)
				)
				(justify left bottom)
				(hide yes)
			)
		)
		(property "Dielectric" ""
			(at 261.62 113.03 0)
			(effects
				(font
					(size 1.27 1.27)
				)
				(justify left bottom)
				(hide yes)
			)
		)
		(property "Author" "Antmicro"
			(at 256.54 113.03 0)
			(effects
				(font
					(size 1.27 1.27)
					(thickness 0.15)
				)
				(justify left bottom)
				(hide yes)
			)
		)
		(pin "1"
		)
		(pin "2"
		)
		(instances
			(project "thunderbolt-gpu-adapter"
				(path ""
					(reference "C80")
					(unit 1)
				)
			)
		)
	)
	(symbol
		(lib_id "antmicropower:GND")
		(at 205.74 134.62 0)
		(unit 1)
		(exclude_from_sim no)
		(in_bom yes)
		(on_board yes)
		(dnp no)
		(property "Reference" "#PWR0223"
			(at 205.74 140.97 0)
			(effects
				(font
					(size 1.27 1.27)
				)
				(hide yes)
			)
		)
		(property "Value" "GND"
			(at 205.74 138.43 0)
			(effects
				(font
					(size 1.27 1.27)
				)
			)
		)
		(property "Footprint" ""
			(at 205.74 134.62 0)
			(effects
				(font
					(size 1.27 1.27)
				)
				(hide yes)
			)
		)
		(property "Datasheet" ""
			(at 205.74 134.62 0)
			(effects
				(font
					(size 1.27 1.27)
				)
				(hide yes)
			)
		)
		(property "Description" ""
			(at 205.74 134.62 0)
			(effects
				(font
					(size 1.27 1.27)
				)
				(hide yes)
			)
		)
		(property "Author" "Antmicro"
			(at 214.63 142.24 0)
			(effects
				(font
					(size 1.27 1.27)
					(thickness 0.15)
				)
				(justify left bottom)
				(hide yes)
			)
		)
		(property "License" "Apache-2.0"
			(at 214.63 144.78 0)
			(effects
				(font
					(size 1.27 1.27)
					(thickness 0.15)
				)
				(justify left bottom)
				(hide yes)
			)
		)
		(pin "1"
		)
		(instances
			(project "thunderbolt-gpu-adapter"
				(path ""
					(reference "#PWR0223")
					(unit 1)
				)
			)
		)
	)
	(symbol
		(lib_id "antmicropower:GND")
		(at 111.76 203.2 0)
		(unit 1)
		(exclude_from_sim no)
		(in_bom yes)
		(on_board yes)
		(dnp no)
		(property "Reference" "#PWR085"
			(at 111.76 209.55 0)
			(effects
				(font
					(size 1.27 1.27)
				)
				(hide yes)
			)
		)
		(property "Value" "GND"
			(at 111.76 207.01 0)
			(effects
				(font
					(size 1.27 1.27)
				)
			)
		)
		(property "Footprint" ""
			(at 111.76 203.2 0)
			(effects
				(font
					(size 1.27 1.27)
				)
				(hide yes)
			)
		)
		(property "Datasheet" ""
			(at 111.76 203.2 0)
			(effects
				(font
					(size 1.27 1.27)
				)
				(hide yes)
			)
		)
		(property "Description" ""
			(at 111.76 203.2 0)
			(effects
				(font
					(size 1.27 1.27)
				)
				(hide yes)
			)
		)
		(property "Author" "Antmicro"
			(at 120.65 210.82 0)
			(effects
				(font
					(size 1.27 1.27)
					(thickness 0.15)
				)
				(justify left bottom)
				(hide yes)
			)
		)
		(property "License" "Apache-2.0"
			(at 120.65 213.36 0)
			(effects
				(font
					(size 1.27 1.27)
					(thickness 0.15)
				)
				(justify left bottom)
				(hide yes)
			)
		)
		(pin "1"
		)
		(instances
			(project "thunderbolt-gpu-adapter"
				(path ""
					(reference "#PWR085")
					(unit 1)
				)
			)
		)
	)
	(symbol
		(lib_id "antmicroCapacitors0402:C_100n_0402")
		(at 186.69 165.1 90)
		(unit 1)
		(exclude_from_sim no)
		(in_bom yes)
		(on_board yes)
		(dnp no)
		(property "Reference" "C92"
			(at 187.325 160.655 90)
			(effects
				(font
					(size 1.27 1.27)
					(thickness 0.15)
				)
				(justify right)
			)
		)
		(property "Value" "C_100n_0402"
			(at 196.85 144.78 0)
			(effects
				(font
					(size 1.27 1.27)
					(thickness 0.15)
				)
				(justify left bottom)
				(hide yes)
			)
		)
		(property "Footprint" "antmicro-footprints:C_0402_1005Metric"
			(at 199.39 144.78 0)
			(effects
				(font
					(size 1.27 1.27)
					(thickness 0.15)
				)
				(justify left bottom)
				(hide yes)
			)
		)
		(property "Datasheet" "https://www.murata.com/products/productdetail?partno=GRM155R61H104KE14%23"
			(at 201.93 144.78 0)
			(effects
				(font
					(size 1.27 1.27)
					(thickness 0.15)
				)
				(justify left bottom)
				(hide yes)
			)
		)
		(property "Description" ""
			(at 186.69 165.1 0)
			(effects
				(font
					(size 1.27 1.27)
				)
				(hide yes)
			)
		)
		(property "MPN" "GRM155R61H104KE14D"
			(at 204.47 144.78 0)
			(effects
				(font
					(size 1.27 1.27)
					(thickness 0.15)
				)
				(justify left bottom)
				(hide yes)
			)
		)
		(property "Manufacturer" "Murata"
			(at 207.01 144.78 0)
			(effects
				(font
					(size 1.27 1.27)
					(thickness 0.15)
				)
				(justify left bottom)
				(hide yes)
			)
		)
		(property "License" "Apache-2.0"
			(at 209.55 144.78 0)
			(effects
				(font
					(size 1.27 1.27)
					(thickness 0.15)
				)
				(justify left bottom)
				(hide yes)
			)
		)
		(property "Val" "100n"
			(at 187.325 164.465 90)
			(effects
				(font
					(size 1.27 1.27)
					(thickness 0.15)
				)
				(justify right)
			)
		)
		(property "Voltage" "50V"
			(at 214.63 144.78 0)
			(effects
				(font
					(size 1.27 1.27)
				)
				(justify left bottom)
				(hide yes)
			)
		)
		(property "Dielectric" "X5R"
			(at 217.17 144.78 0)
			(effects
				(font
					(size 1.27 1.27)
				)
				(justify left bottom)
				(hide yes)
			)
		)
		(property "Author" "Antmicro"
			(at 212.09 144.78 0)
			(effects
				(font
					(size 1.27 1.27)
					(thickness 0.15)
				)
				(justify left bottom)
				(hide yes)
			)
		)
		(pin "1"
		)
		(pin "2"
		)
		(instances
			(project "thunderbolt-gpu-adapter"
				(path ""
					(reference "C92")
					(unit 1)
				)
			)
		)
	)
	(symbol
		(lib_id "antmicropower:GND")
		(at 205.74 203.2 0)
		(unit 1)
		(exclude_from_sim no)
		(in_bom yes)
		(on_board yes)
		(dnp no)
		(property "Reference" "#PWR0117"
			(at 205.74 209.55 0)
			(effects
				(font
					(size 1.27 1.27)
				)
				(hide yes)
			)
		)
		(property "Value" "GND"
			(at 205.74 207.01 0)
			(effects
				(font
					(size 1.27 1.27)
				)
			)
		)
		(property "Footprint" ""
			(at 205.74 203.2 0)
			(effects
				(font
					(size 1.27 1.27)
				)
				(hide yes)
			)
		)
		(property "Datasheet" ""
			(at 205.74 203.2 0)
			(effects
				(font
					(size 1.27 1.27)
				)
				(hide yes)
			)
		)
		(property "Description" ""
			(at 205.74 203.2 0)
			(effects
				(font
					(size 1.27 1.27)
				)
				(hide yes)
			)
		)
		(property "Author" "Antmicro"
			(at 214.63 210.82 0)
			(effects
				(font
					(size 1.27 1.27)
					(thickness 0.15)
				)
				(justify left bottom)
				(hide yes)
			)
		)
		(property "License" "Apache-2.0"
			(at 214.63 213.36 0)
			(effects
				(font
					(size 1.27 1.27)
					(thickness 0.15)
				)
				(justify left bottom)
				(hide yes)
			)
		)
		(pin "1"
		)
		(instances
			(project "thunderbolt-gpu-adapter"
				(path ""
					(reference "#PWR0117")
					(unit 1)
				)
			)
		)
	)
	(symbol
		(lib_id "antmicroCapacitors0402:C_10u_0402")
		(at 199.39 222.25 90)
		(unit 1)
		(exclude_from_sim no)
		(in_bom yes)
		(on_board yes)
		(dnp no)
		(fields_autoplaced yes)
		(property "Reference" "C75"
			(at 200.025 217.805 90)
			(effects
				(font
					(size 1.27 1.27)
					(thickness 0.15)
				)
				(justify right)
			)
		)
		(property "Value" "C_10u_0402"
			(at 209.55 201.93 0)
			(effects
				(font
					(size 1.27 1.27)
					(thickness 0.15)
				)
				(justify left bottom)
				(hide yes)
			)
		)
		(property "Footprint" "antmicro-footprints:C_0402_1005Metric"
			(at 212.09 201.93 0)
			(effects
				(font
					(size 1.27 1.27)
					(thickness 0.15)
				)
				(justify left bottom)
				(hide yes)
			)
		)
		(property "Datasheet" "https://www.yageo.com/en/Chart/Download/pdf/CC0402MRX5R5BB106"
			(at 214.63 201.93 0)
			(effects
				(font
					(size 1.27 1.27)
					(thickness 0.15)
				)
				(justify left bottom)
				(hide yes)
			)
		)
		(property "Description" ""
			(at 199.39 222.25 0)
			(effects
				(font
					(size 1.27 1.27)
				)
				(hide yes)
			)
		)
		(property "MPN" "CC0402MRX5R5BB106"
			(at 217.17 201.93 0)
			(effects
				(font
					(size 1.27 1.27)
					(thickness 0.15)
				)
				(justify left bottom)
				(hide yes)
			)
		)
		(property "Manufacturer" "YAGEO"
			(at 219.71 201.93 0)
			(effects
				(font
					(size 1.27 1.27)
					(thickness 0.15)
				)
				(justify left bottom)
				(hide yes)
			)
		)
		(property "License" "Apache-2.0"
			(at 222.25 201.93 0)
			(effects
				(font
					(size 1.27 1.27)
					(thickness 0.15)
				)
				(justify left bottom)
				(hide yes)
			)
		)
		(property "Val" "10u"
			(at 200.025 221.615 90)
			(effects
				(font
					(size 1.27 1.27)
					(thickness 0.15)
				)
				(justify right)
			)
		)
		(property "Voltage" ""
			(at 227.33 201.93 0)
			(effects
				(font
					(size 1.27 1.27)
				)
				(justify left bottom)
				(hide yes)
			)
		)
		(property "Dielectric" ""
			(at 229.87 201.93 0)
			(effects
				(font
					(size 1.27 1.27)
				)
				(justify left bottom)
				(hide yes)
			)
		)
		(property "Author" "Antmicro"
			(at 224.79 201.93 0)
			(effects
				(font
					(size 1.27 1.27)
					(thickness 0.15)
				)
				(justify left bottom)
				(hide yes)
			)
		)
		(pin "1"
		)
		(pin "2"
		)
		(instances
			(project "thunderbolt-gpu-adapter"
				(path ""
					(reference "C75")
					(unit 1)
				)
			)
		)
	)
	(symbol
		(lib_id "antmicroCapacitors0402:C_1u_0402")
		(at 180.34 166.37 270)
		(mirror x)
		(unit 1)
		(exclude_from_sim no)
		(in_bom yes)
		(on_board yes)
		(dnp no)
		(property "Reference" "C71"
			(at 177.8 162.5536 90)
			(effects
				(font
					(size 1.27 1.27)
					(thickness 0.15)
				)
				(justify right)
			)
		)
		(property "Value" "C_1u_0402"
			(at 170.18 146.05 0)
			(effects
				(font
					(size 1.27 1.27)
					(thickness 0.15)
				)
				(justify left bottom)
				(hide yes)
			)
		)
		(property "Footprint" "antmicro-footprints:C_0402_1005Metric"
			(at 167.64 146.05 0)
			(effects
				(font
					(size 1.27 1.27)
					(thickness 0.15)
				)
				(justify left bottom)
				(hide yes)
			)
		)
		(property "Datasheet" "https://product.tdk.com/en/search/capacitor/ceramic/mlcc/info?part_no=C1005X6S1A105K050BC"
			(at 165.1 146.05 0)
			(effects
				(font
					(size 1.27 1.27)
					(thickness 0.15)
				)
				(justify left bottom)
				(hide yes)
			)
		)
		(property "Description" ""
			(at 180.34 166.37 0)
			(effects
				(font
					(size 1.27 1.27)
				)
				(hide yes)
			)
		)
		(property "MPN" "C1005X6S1A105K050BC"
			(at 162.56 146.05 0)
			(effects
				(font
					(size 1.27 1.27)
					(thickness 0.15)
				)
				(justify left bottom)
				(hide yes)
			)
		)
		(property "Manufacturer" "TDK"
			(at 160.02 146.05 0)
			(effects
				(font
					(size 1.27 1.27)
					(thickness 0.15)
				)
				(justify left bottom)
				(hide yes)
			)
		)
		(property "License" "Apache-2.0"
			(at 157.48 146.05 0)
			(effects
				(font
					(size 1.27 1.27)
					(thickness 0.15)
				)
				(justify left bottom)
				(hide yes)
			)
		)
		(property "Val" "1u"
			(at 177.8 165.0936 90)
			(effects
				(font
					(size 1.27 1.27)
					(thickness 0.15)
				)
				(justify right)
			)
		)
		(property "Voltage" ""
			(at 152.4 146.05 0)
			(effects
				(font
					(size 1.27 1.27)
				)
				(justify left bottom)
				(hide yes)
			)
		)
		(property "Dielectric" ""
			(at 149.86 146.05 0)
			(effects
				(font
					(size 1.27 1.27)
				)
				(justify left bottom)
				(hide yes)
			)
		)
		(property "Author" "Antmicro"
			(at 154.94 146.05 0)
			(effects
				(font
					(size 1.27 1.27)
					(thickness 0.15)
				)
				(justify left bottom)
				(hide yes)
			)
		)
		(pin "1"
		)
		(pin "2"
		)
		(instances
			(project "thunderbolt-gpu-adapter"
				(path ""
					(reference "C71")
					(unit 1)
				)
			)
		)
	)
	(symbol
		(lib_id "antmicroCapacitors0402:C_10u_0402")
		(at 199.39 165.1 90)
		(unit 1)
		(exclude_from_sim no)
		(in_bom yes)
		(on_board yes)
		(dnp no)
		(fields_autoplaced yes)
		(property "Reference" "C96"
			(at 200.025 160.655 90)
			(effects
				(font
					(size 1.27 1.27)
					(thickness 0.15)
				)
				(justify right)
			)
		)
		(property "Value" "C_10u_0402"
			(at 209.55 144.78 0)
			(effects
				(font
					(size 1.27 1.27)
					(thickness 0.15)
				)
				(justify left bottom)
				(hide yes)
			)
		)
		(property "Footprint" "antmicro-footprints:C_0402_1005Metric"
			(at 212.09 144.78 0)
			(effects
				(font
					(size 1.27 1.27)
					(thickness 0.15)
				)
				(justify left bottom)
				(hide yes)
			)
		)
		(property "Datasheet" "https://www.yageo.com/en/Chart/Download/pdf/CC0402MRX5R5BB106"
			(at 214.63 144.78 0)
			(effects
				(font
					(size 1.27 1.27)
					(thickness 0.15)
				)
				(justify left bottom)
				(hide yes)
			)
		)
		(property "Description" ""
			(at 199.39 165.1 0)
			(effects
				(font
					(size 1.27 1.27)
				)
				(hide yes)
			)
		)
		(property "MPN" "CC0402MRX5R5BB106"
			(at 217.17 144.78 0)
			(effects
				(font
					(size 1.27 1.27)
					(thickness 0.15)
				)
				(justify left bottom)
				(hide yes)
			)
		)
		(property "Manufacturer" "YAGEO"
			(at 219.71 144.78 0)
			(effects
				(font
					(size 1.27 1.27)
					(thickness 0.15)
				)
				(justify left bottom)
				(hide yes)
			)
		)
		(property "License" "Apache-2.0"
			(at 222.25 144.78 0)
			(effects
				(font
					(size 1.27 1.27)
					(thickness 0.15)
				)
				(justify left bottom)
				(hide yes)
			)
		)
		(property "Val" "10u"
			(at 200.025 164.465 90)
			(effects
				(font
					(size 1.27 1.27)
					(thickness 0.15)
				)
				(justify right)
			)
		)
		(property "Voltage" ""
			(at 227.33 144.78 0)
			(effects
				(font
					(size 1.27 1.27)
				)
				(justify left bottom)
				(hide yes)
			)
		)
		(property "Dielectric" ""
			(at 229.87 144.78 0)
			(effects
				(font
					(size 1.27 1.27)
				)
				(justify left bottom)
				(hide yes)
			)
		)
		(property "Author" "Antmicro"
			(at 224.79 144.78 0)
			(effects
				(font
					(size 1.27 1.27)
					(thickness 0.15)
				)
				(justify left bottom)
				(hide yes)
			)
		)
		(pin "1"
		)
		(pin "2"
		)
		(instances
			(project "thunderbolt-gpu-adapter"
				(path ""
					(reference "C96")
					(unit 1)
				)
			)
		)
	)
	(symbol
		(lib_id "antmicroResistors0402:R_100k_0402")
		(at 207.01 289.56 90)
		(unit 1)
		(exclude_from_sim no)
		(in_bom yes)
		(on_board yes)
		(dnp no)
		(property "Reference" "R48"
			(at 208.28 285.75 90)
			(effects
				(font
					(size 1.27 1.27)
					(thickness 0.15)
				)
				(justify right)
			)
		)
		(property "Value" "R_100k_0402"
			(at 219.71 269.24 0)
			(effects
				(font
					(size 1.27 1.27)
					(thickness 0.15)
				)
				(justify left bottom)
				(hide yes)
			)
		)
		(property "Footprint" "antmicro-footprints:R_0402_1005Metric"
			(at 222.25 269.24 0)
			(effects
				(font
					(size 1.27 1.27)
					(thickness 0.15)
				)
				(justify left bottom)
				(hide yes)
			)
		)
		(property "Datasheet" "https://www.bourns.com/docs/product-datasheets/cr.pdf"
			(at 224.79 269.24 0)
			(effects
				(font
					(size 1.27 1.27)
					(thickness 0.15)
				)
				(justify left bottom)
				(hide yes)
			)
		)
		(property "Description" ""
			(at 207.01 289.56 0)
			(effects
				(font
					(size 1.27 1.27)
				)
				(hide yes)
			)
		)
		(property "MPN" "CR0402-FX-1003GLF"
			(at 227.33 269.24 0)
			(effects
				(font
					(size 1.27 1.27)
					(thickness 0.15)
				)
				(justify left bottom)
				(hide yes)
			)
		)
		(property "Manufacturer" "Bourns"
			(at 229.87 269.24 0)
			(effects
				(font
					(size 1.27 1.27)
					(thickness 0.15)
				)
				(justify left bottom)
				(hide yes)
			)
		)
		(property "License" "Apache-2.0"
			(at 232.41 269.24 0)
			(effects
				(font
					(size 1.27 1.27)
					(thickness 0.15)
				)
				(justify left bottom)
				(hide yes)
			)
		)
		(property "Val" "100k"
			(at 208.28 288.29 90)
			(effects
				(font
					(size 1.27 1.27)
					(thickness 0.15)
				)
				(justify right)
			)
		)
		(property "Tolerance" "1%"
			(at 217.17 269.24 0)
			(effects
				(font
					(size 1.27 1.27)
				)
				(justify left bottom)
				(hide yes)
			)
		)
		(property "Author" "Antmicro"
			(at 234.95 269.24 0)
			(effects
				(font
					(size 1.27 1.27)
					(thickness 0.15)
				)
				(justify left bottom)
				(hide yes)
			)
		)
		(pin "1"
		)
		(pin "2"
		)
		(instances
			(project "thunderbolt-gpu-adapter"
				(path ""
					(reference "R48")
					(unit 1)
				)
			)
		)
	)
	(symbol
		(lib_id "antmicroCapacitors0402:C_1u_0402")
		(at 193.04 165.1 90)
		(unit 1)
		(exclude_from_sim no)
		(in_bom yes)
		(on_board yes)
		(dnp no)
		(fields_autoplaced yes)
		(property "Reference" "C94"
			(at 193.675 160.655 90)
			(effects
				(font
					(size 1.27 1.27)
					(thickness 0.15)
				)
				(justify right)
			)
		)
		(property "Value" "C_1u_0402"
			(at 203.2 144.78 0)
			(effects
				(font
					(size 1.27 1.27)
					(thickness 0.15)
				)
				(justify left bottom)
				(hide yes)
			)
		)
		(property "Footprint" "antmicro-footprints:C_0402_1005Metric"
			(at 205.74 144.78 0)
			(effects
				(font
					(size 1.27 1.27)
					(thickness 0.15)
				)
				(justify left bottom)
				(hide yes)
			)
		)
		(property "Datasheet" "https://product.tdk.com/en/search/capacitor/ceramic/mlcc/info?part_no=C1005X6S1A105K050BC"
			(at 208.28 144.78 0)
			(effects
				(font
					(size 1.27 1.27)
					(thickness 0.15)
				)
				(justify left bottom)
				(hide yes)
			)
		)
		(property "Description" ""
			(at 193.04 165.1 0)
			(effects
				(font
					(size 1.27 1.27)
				)
				(hide yes)
			)
		)
		(property "MPN" "C1005X6S1A105K050BC"
			(at 210.82 144.78 0)
			(effects
				(font
					(size 1.27 1.27)
					(thickness 0.15)
				)
				(justify left bottom)
				(hide yes)
			)
		)
		(property "Manufacturer" "TDK"
			(at 213.36 144.78 0)
			(effects
				(font
					(size 1.27 1.27)
					(thickness 0.15)
				)
				(justify left bottom)
				(hide yes)
			)
		)
		(property "License" "Apache-2.0"
			(at 215.9 144.78 0)
			(effects
				(font
					(size 1.27 1.27)
					(thickness 0.15)
				)
				(justify left bottom)
				(hide yes)
			)
		)
		(property "Val" "1u"
			(at 193.675 164.465 90)
			(effects
				(font
					(size 1.27 1.27)
					(thickness 0.15)
				)
				(justify right)
			)
		)
		(property "Voltage" ""
			(at 220.98 144.78 0)
			(effects
				(font
					(size 1.27 1.27)
				)
				(justify left bottom)
				(hide yes)
			)
		)
		(property "Dielectric" ""
			(at 223.52 144.78 0)
			(effects
				(font
					(size 1.27 1.27)
				)
				(justify left bottom)
				(hide yes)
			)
		)
		(property "Author" "Antmicro"
			(at 218.44 144.78 0)
			(effects
				(font
					(size 1.27 1.27)
					(thickness 0.15)
				)
				(justify left bottom)
				(hide yes)
			)
		)
		(pin "1"
		)
		(pin "2"
		)
		(instances
			(project "thunderbolt-gpu-adapter"
				(path ""
					(reference "C94")
					(unit 1)
				)
			)
		)
	)
	(symbol
		(lib_id "antmicropower:GND")
		(at 93.98 151.13 0)
		(unit 1)
		(exclude_from_sim no)
		(in_bom yes)
		(on_board yes)
		(dnp no)
		(property "Reference" "#PWR080"
			(at 93.98 157.48 0)
			(effects
				(font
					(size 1.27 1.27)
				)
				(hide yes)
			)
		)
		(property "Value" "GND"
			(at 93.98 154.94 0)
			(effects
				(font
					(size 1.27 1.27)
				)
			)
		)
		(property "Footprint" ""
			(at 93.98 151.13 0)
			(effects
				(font
					(size 1.27 1.27)
				)
				(hide yes)
			)
		)
		(property "Datasheet" ""
			(at 93.98 151.13 0)
			(effects
				(font
					(size 1.27 1.27)
				)
				(hide yes)
			)
		)
		(property "Description" ""
			(at 93.98 151.13 0)
			(effects
				(font
					(size 1.27 1.27)
				)
				(hide yes)
			)
		)
		(property "Author" "Antmicro"
			(at 102.87 158.75 0)
			(effects
				(font
					(size 1.27 1.27)
					(thickness 0.15)
				)
				(justify left bottom)
				(hide yes)
			)
		)
		(property "License" "Apache-2.0"
			(at 102.87 161.29 0)
			(effects
				(font
					(size 1.27 1.27)
					(thickness 0.15)
				)
				(justify left bottom)
				(hide yes)
			)
		)
		(pin "1"
		)
		(instances
			(project "thunderbolt-gpu-adapter"
				(path ""
					(reference "#PWR080")
					(unit 1)
				)
			)
		)
	)
	(symbol
		(lib_id "antmicroCapacitors0402:C_10u_0402")
		(at 237.49 133.35 90)
		(unit 1)
		(exclude_from_sim no)
		(in_bom yes)
		(on_board yes)
		(dnp no)
		(property "Reference" "C83"
			(at 238.125 128.905 90)
			(effects
				(font
					(size 1.27 1.27)
					(thickness 0.15)
				)
				(justify right)
			)
		)
		(property "Value" "C_10u_0402"
			(at 247.65 113.03 0)
			(effects
				(font
					(size 1.27 1.27)
					(thickness 0.15)
				)
				(justify left bottom)
				(hide yes)
			)
		)
		(property "Footprint" "antmicro-footprints:C_0402_1005Metric"
			(at 250.19 113.03 0)
			(effects
				(font
					(size 1.27 1.27)
					(thickness 0.15)
				)
				(justify left bottom)
				(hide yes)
			)
		)
		(property "Datasheet" "https://www.yageo.com/en/Chart/Download/pdf/CC0402MRX5R5BB106"
			(at 252.73 113.03 0)
			(effects
				(font
					(size 1.27 1.27)
					(thickness 0.15)
				)
				(justify left bottom)
				(hide yes)
			)
		)
		(property "Description" ""
			(at 237.49 133.35 0)
			(effects
				(font
					(size 1.27 1.27)
				)
				(hide yes)
			)
		)
		(property "MPN" "CC0402MRX5R5BB106"
			(at 255.27 113.03 0)
			(effects
				(font
					(size 1.27 1.27)
					(thickness 0.15)
				)
				(justify left bottom)
				(hide yes)
			)
		)
		(property "Manufacturer" "YAGEO"
			(at 257.81 113.03 0)
			(effects
				(font
					(size 1.27 1.27)
					(thickness 0.15)
				)
				(justify left bottom)
				(hide yes)
			)
		)
		(property "License" "Apache-2.0"
			(at 260.35 113.03 0)
			(effects
				(font
					(size 1.27 1.27)
					(thickness 0.15)
				)
				(justify left bottom)
				(hide yes)
			)
		)
		(property "Val" "10u"
			(at 238.125 132.715 90)
			(effects
				(font
					(size 1.27 1.27)
					(thickness 0.15)
				)
				(justify right)
			)
		)
		(property "Voltage" ""
			(at 265.43 113.03 0)
			(effects
				(font
					(size 1.27 1.27)
				)
				(justify left bottom)
				(hide yes)
			)
		)
		(property "Dielectric" ""
			(at 267.97 113.03 0)
			(effects
				(font
					(size 1.27 1.27)
				)
				(justify left bottom)
				(hide yes)
			)
		)
		(property "Author" "Antmicro"
			(at 262.89 113.03 0)
			(effects
				(font
					(size 1.27 1.27)
					(thickness 0.15)
				)
				(justify left bottom)
				(hide yes)
			)
		)
		(pin "1"
		)
		(pin "2"
		)
		(instances
			(project "thunderbolt-gpu-adapter"
				(path ""
					(reference "C83")
					(unit 1)
				)
			)
		)
	)
	(symbol
		(lib_id "antmicroResistors0402:R_47k_0402")
		(at 236.22 208.28 0)
		(unit 1)
		(exclude_from_sim no)
		(in_bom yes)
		(on_board yes)
		(dnp no)
		(fields_autoplaced yes)
		(property "Reference" "R136"
			(at 238.76 201.93 0)
			(effects
				(font
					(size 1.27 1.27)
					(thickness 0.15)
				)
			)
		)
		(property "Value" "R_47k_0402"
			(at 256.54 220.98 0)
			(effects
				(font
					(size 1.27 1.27)
					(thickness 0.15)
				)
				(justify left bottom)
				(hide yes)
			)
		)
		(property "Footprint" "antmicro-footprints:R_0402_1005Metric"
			(at 256.54 223.52 0)
			(effects
				(font
					(size 1.27 1.27)
					(thickness 0.15)
				)
				(justify left bottom)
				(hide yes)
			)
		)
		(property "Datasheet" "https://www.bourns.com/docs/product-datasheets/cr.pdf"
			(at 256.54 226.06 0)
			(effects
				(font
					(size 1.27 1.27)
					(thickness 0.15)
				)
				(justify left bottom)
				(hide yes)
			)
		)
		(property "Description" ""
			(at 236.22 208.28 0)
			(effects
				(font
					(size 1.27 1.27)
				)
				(hide yes)
			)
		)
		(property "MPN" "CR0402-FX-4702GLF"
			(at 256.54 228.6 0)
			(effects
				(font
					(size 1.27 1.27)
					(thickness 0.15)
				)
				(justify left bottom)
				(hide yes)
			)
		)
		(property "Manufacturer" "Bourns"
			(at 256.54 231.14 0)
			(effects
				(font
					(size 1.27 1.27)
					(thickness 0.15)
				)
				(justify left bottom)
				(hide yes)
			)
		)
		(property "License" "Apache-2.0"
			(at 256.54 233.68 0)
			(effects
				(font
					(size 1.27 1.27)
					(thickness 0.15)
				)
				(justify left bottom)
				(hide yes)
			)
		)
		(property "Author" "Antmicro"
			(at 256.54 236.22 0)
			(effects
				(font
					(size 1.27 1.27)
					(thickness 0.15)
				)
				(justify left bottom)
				(hide yes)
			)
		)
		(property "Val" "47k"
			(at 238.76 204.47 0)
			(effects
				(font
					(size 1.27 1.27)
					(thickness 0.15)
				)
			)
		)
		(property "Tolerance" "1%"
			(at 256.54 218.44 0)
			(effects
				(font
					(size 1.27 1.27)
				)
				(justify left bottom)
				(hide yes)
			)
		)
		(pin "1"
		)
		(pin "2"
		)
		(instances
			(project "thunderbolt-gpu-adapter"
				(path ""
					(reference "R136")
					(unit 1)
				)
			)
		)
	)
	(symbol
		(lib_id "antmicropower:GND")
		(at 207.01 292.1 0)
		(unit 1)
		(exclude_from_sim no)
		(in_bom yes)
		(on_board yes)
		(dnp no)
		(property "Reference" "#PWR0125"
			(at 207.01 298.45 0)
			(effects
				(font
					(size 1.27 1.27)
				)
				(hide yes)
			)
		)
		(property "Value" "GND"
			(at 207.01 295.91 0)
			(effects
				(font
					(size 1.27 1.27)
				)
			)
		)
		(property "Footprint" ""
			(at 207.01 292.1 0)
			(effects
				(font
					(size 1.27 1.27)
				)
				(hide yes)
			)
		)
		(property "Datasheet" ""
			(at 207.01 292.1 0)
			(effects
				(font
					(size 1.27 1.27)
				)
				(hide yes)
			)
		)
		(property "Description" ""
			(at 207.01 292.1 0)
			(effects
				(font
					(size 1.27 1.27)
				)
				(hide yes)
			)
		)
		(property "Author" "Antmicro"
			(at 215.9 299.72 0)
			(effects
				(font
					(size 1.27 1.27)
					(thickness 0.15)
				)
				(justify left bottom)
				(hide yes)
			)
		)
		(property "License" "Apache-2.0"
			(at 215.9 302.26 0)
			(effects
				(font
					(size 1.27 1.27)
					(thickness 0.15)
				)
				(justify left bottom)
				(hide yes)
			)
		)
		(pin "1"
		)
		(instances
			(project "thunderbolt-gpu-adapter"
				(path ""
					(reference "#PWR0125")
					(unit 1)
				)
			)
		)
	)
	(symbol
		(lib_id "antmicropower:GND")
		(at 100.33 151.13 0)
		(unit 1)
		(exclude_from_sim no)
		(in_bom yes)
		(on_board yes)
		(dnp no)
		(property "Reference" "#PWR083"
			(at 100.33 157.48 0)
			(effects
				(font
					(size 1.27 1.27)
				)
				(hide yes)
			)
		)
		(property "Value" "GND"
			(at 100.33 154.94 0)
			(effects
				(font
					(size 1.27 1.27)
				)
			)
		)
		(property "Footprint" ""
			(at 100.33 151.13 0)
			(effects
				(font
					(size 1.27 1.27)
				)
				(hide yes)
			)
		)
		(property "Datasheet" ""
			(at 100.33 151.13 0)
			(effects
				(font
					(size 1.27 1.27)
				)
				(hide yes)
			)
		)
		(property "Description" ""
			(at 100.33 151.13 0)
			(effects
				(font
					(size 1.27 1.27)
				)
				(hide yes)
			)
		)
		(property "Author" "Antmicro"
			(at 109.22 158.75 0)
			(effects
				(font
					(size 1.27 1.27)
					(thickness 0.15)
				)
				(justify left bottom)
				(hide yes)
			)
		)
		(property "License" "Apache-2.0"
			(at 109.22 161.29 0)
			(effects
				(font
					(size 1.27 1.27)
					(thickness 0.15)
				)
				(justify left bottom)
				(hide yes)
			)
		)
		(pin "1"
		)
		(instances
			(project "thunderbolt-gpu-adapter"
				(path ""
					(reference "#PWR083")
					(unit 1)
				)
			)
		)
	)
	(symbol
		(lib_id "antmicropower:GND")
		(at 116.84 168.91 0)
		(unit 1)
		(exclude_from_sim no)
		(in_bom yes)
		(on_board yes)
		(dnp no)
		(property "Reference" "#PWR093"
			(at 116.84 175.26 0)
			(effects
				(font
					(size 1.27 1.27)
				)
				(hide yes)
			)
		)
		(property "Value" "GND"
			(at 116.84 172.72 0)
			(effects
				(font
					(size 1.27 1.27)
				)
			)
		)
		(property "Footprint" ""
			(at 116.84 168.91 0)
			(effects
				(font
					(size 1.27 1.27)
				)
				(hide yes)
			)
		)
		(property "Datasheet" ""
			(at 116.84 168.91 0)
			(effects
				(font
					(size 1.27 1.27)
				)
				(hide yes)
			)
		)
		(property "Description" ""
			(at 116.84 168.91 0)
			(effects
				(font
					(size 1.27 1.27)
				)
				(hide yes)
			)
		)
		(property "Author" "Antmicro"
			(at 125.73 176.53 0)
			(effects
				(font
					(size 1.27 1.27)
					(thickness 0.15)
				)
				(justify left bottom)
				(hide yes)
			)
		)
		(property "License" "Apache-2.0"
			(at 125.73 179.07 0)
			(effects
				(font
					(size 1.27 1.27)
					(thickness 0.15)
				)
				(justify left bottom)
				(hide yes)
			)
		)
		(pin "1"
		)
		(instances
			(project "thunderbolt-gpu-adapter"
				(path ""
					(reference "#PWR093")
					(unit 1)
				)
			)
		)
	)
	(symbol
		(lib_id "antmicropower:GND")
		(at 111.76 151.13 0)
		(unit 1)
		(exclude_from_sim no)
		(in_bom yes)
		(on_board yes)
		(dnp no)
		(property "Reference" "#PWR089"
			(at 111.76 157.48 0)
			(effects
				(font
					(size 1.27 1.27)
				)
				(hide yes)
			)
		)
		(property "Value" "GND"
			(at 111.76 154.94 0)
			(effects
				(font
					(size 1.27 1.27)
				)
			)
		)
		(property "Footprint" ""
			(at 111.76 151.13 0)
			(effects
				(font
					(size 1.27 1.27)
				)
				(hide yes)
			)
		)
		(property "Datasheet" ""
			(at 111.76 151.13 0)
			(effects
				(font
					(size 1.27 1.27)
				)
				(hide yes)
			)
		)
		(property "Description" ""
			(at 111.76 151.13 0)
			(effects
				(font
					(size 1.27 1.27)
				)
				(hide yes)
			)
		)
		(property "Author" "Antmicro"
			(at 120.65 158.75 0)
			(effects
				(font
					(size 1.27 1.27)
					(thickness 0.15)
				)
				(justify left bottom)
				(hide yes)
			)
		)
		(property "License" "Apache-2.0"
			(at 120.65 161.29 0)
			(effects
				(font
					(size 1.27 1.27)
					(thickness 0.15)
				)
				(justify left bottom)
				(hide yes)
			)
		)
		(pin "1"
		)
		(instances
			(project "thunderbolt-gpu-adapter"
				(path ""
					(reference "#PWR089")
					(unit 1)
				)
			)
		)
	)
	(symbol
		(lib_id "antmicropower:GND")
		(at 121.92 224.79 0)
		(unit 1)
		(exclude_from_sim no)
		(in_bom yes)
		(on_board yes)
		(dnp no)
		(property "Reference" "#PWR0292"
			(at 121.92 231.14 0)
			(effects
				(font
					(size 1.27 1.27)
				)
				(hide yes)
			)
		)
		(property "Value" "GND"
			(at 121.92 228.6 0)
			(effects
				(font
					(size 1.27 1.27)
				)
			)
		)
		(property "Footprint" ""
			(at 121.92 224.79 0)
			(effects
				(font
					(size 1.27 1.27)
				)
				(hide yes)
			)
		)
		(property "Datasheet" ""
			(at 121.92 224.79 0)
			(effects
				(font
					(size 1.27 1.27)
				)
				(hide yes)
			)
		)
		(property "Description" ""
			(at 121.92 224.79 0)
			(effects
				(font
					(size 1.27 1.27)
				)
				(hide yes)
			)
		)
		(property "Author" "Antmicro"
			(at 130.81 232.41 0)
			(effects
				(font
					(size 1.27 1.27)
					(thickness 0.15)
				)
				(justify left bottom)
				(hide yes)
			)
		)
		(property "License" "Apache-2.0"
			(at 130.81 234.95 0)
			(effects
				(font
					(size 1.27 1.27)
					(thickness 0.15)
				)
				(justify left bottom)
				(hide yes)
			)
		)
		(pin "1"
		)
		(instances
			(project "thunderbolt-gpu-adapter"
				(path ""
					(reference "#PWR0292")
					(unit 1)
				)
			)
		)
	)
	(symbol
		(lib_id "antmicropower:GND")
		(at 180.34 167.64 0)
		(unit 1)
		(exclude_from_sim no)
		(in_bom yes)
		(on_board yes)
		(dnp no)
		(property "Reference" "#PWR0101"
			(at 180.34 173.99 0)
			(effects
				(font
					(size 1.27 1.27)
				)
				(hide yes)
			)
		)
		(property "Value" "GND"
			(at 180.34 171.45 0)
			(effects
				(font
					(size 1.27 1.27)
				)
			)
		)
		(property "Footprint" ""
			(at 180.34 167.64 0)
			(effects
				(font
					(size 1.27 1.27)
				)
				(hide yes)
			)
		)
		(property "Datasheet" ""
			(at 180.34 167.64 0)
			(effects
				(font
					(size 1.27 1.27)
				)
				(hide yes)
			)
		)
		(property "Description" ""
			(at 180.34 167.64 0)
			(effects
				(font
					(size 1.27 1.27)
				)
				(hide yes)
			)
		)
		(property "Author" "Antmicro"
			(at 189.23 175.26 0)
			(effects
				(font
					(size 1.27 1.27)
					(thickness 0.15)
				)
				(justify left bottom)
				(hide yes)
			)
		)
		(property "License" "Apache-2.0"
			(at 189.23 177.8 0)
			(effects
				(font
					(size 1.27 1.27)
					(thickness 0.15)
				)
				(justify left bottom)
				(hide yes)
			)
		)
		(pin "1"
		)
		(instances
			(project "thunderbolt-gpu-adapter"
				(path ""
					(reference "#PWR0101")
					(unit 1)
				)
			)
		)
	)
	(symbol
		(lib_id "antmicropower:GND")
		(at 116.84 186.69 0)
		(unit 1)
		(exclude_from_sim no)
		(in_bom yes)
		(on_board yes)
		(dnp no)
		(property "Reference" "#PWR077"
			(at 116.84 193.04 0)
			(effects
				(font
					(size 1.27 1.27)
				)
				(hide yes)
			)
		)
		(property "Value" "GND"
			(at 116.84 190.5 0)
			(effects
				(font
					(size 1.27 1.27)
				)
			)
		)
		(property "Footprint" ""
			(at 116.84 186.69 0)
			(effects
				(font
					(size 1.27 1.27)
				)
				(hide yes)
			)
		)
		(property "Datasheet" ""
			(at 116.84 186.69 0)
			(effects
				(font
					(size 1.27 1.27)
				)
				(hide yes)
			)
		)
		(property "Description" ""
			(at 116.84 186.69 0)
			(effects
				(font
					(size 1.27 1.27)
				)
				(hide yes)
			)
		)
		(property "Author" "Antmicro"
			(at 125.73 194.31 0)
			(effects
				(font
					(size 1.27 1.27)
					(thickness 0.15)
				)
				(justify left bottom)
				(hide yes)
			)
		)
		(property "License" "Apache-2.0"
			(at 125.73 196.85 0)
			(effects
				(font
					(size 1.27 1.27)
					(thickness 0.15)
				)
				(justify left bottom)
				(hide yes)
			)
		)
		(pin "1"
		)
		(instances
			(project "thunderbolt-gpu-adapter"
				(path ""
					(reference "#PWR077")
					(unit 1)
				)
			)
		)
	)
	(symbol
		(lib_id "antmicropower:PWR_FLAG")
		(at 88.9 191.77 0)
		(mirror y)
		(unit 1)
		(exclude_from_sim no)
		(in_bom yes)
		(on_board yes)
		(dnp no)
		(property "Reference" "#FLG0108"
			(at 88.9 189.865 0)
			(effects
				(font
					(size 1.27 1.27)
				)
				(hide yes)
			)
		)
		(property "Value" "PWR_FLAG"
			(at 98.425 194.31 0)
			(effects
				(font
					(size 1.27 1.27)
				)
				(justify left)
			)
		)
		(property "Footprint" ""
			(at 88.9 191.77 0)
			(effects
				(font
					(size 1.27 1.27)
				)
				(hide yes)
			)
		)
		(property "Datasheet" ""
			(at 88.9 191.77 0)
			(effects
				(font
					(size 1.27 1.27)
				)
				(hide yes)
			)
		)
		(property "Description" ""
			(at 88.9 191.77 0)
			(effects
				(font
					(size 1.27 1.27)
				)
				(hide yes)
			)
		)
		(pin "1"
		)
		(instances
			(project "thunderbolt-gpu-adapter"
				(path ""
					(reference "#FLG0108")
					(unit 1)
				)
			)
		)
	)
	(symbol
		(lib_id "antmicroFixedInductors:L_1u_1.8A_0603")
		(at 203.2 157.48 0)
		(unit 1)
		(exclude_from_sim no)
		(in_bom yes)
		(on_board yes)
		(dnp no)
		(fields_autoplaced yes)
		(property "Reference" "L4"
			(at 205.74 152.4 0)
			(effects
				(font
					(size 1.27 1.27)
					(thickness 0.15)
				)
			)
		)
		(property "Value" "L_1u_1.8A_0603"
			(at 217.17 160.02 0)
			(effects
				(font
					(size 1.27 1.27)
					(thickness 0.15)
				)
				(justify left bottom)
				(hide yes)
			)
		)
		(property "Footprint" "antmicro-footprints:L_0603_1608Metric"
			(at 217.17 165.1 0)
			(effects
				(font
					(size 1.27 1.27)
					(thickness 0.15)
				)
				(justify left bottom)
				(hide yes)
			)
		)
		(property "Datasheet" "https://search.murata.co.jp/Ceramy/image/img/P02/JETE243A-0041.pdf"
			(at 217.17 167.64 0)
			(effects
				(font
					(size 1.27 1.27)
					(thickness 0.15)
				)
				(justify left bottom)
				(hide yes)
			)
		)
		(property "Description" ""
			(at 203.2 157.48 0)
			(effects
				(font
					(size 1.27 1.27)
				)
				(hide yes)
			)
		)
		(property "Val" "1u/1.8A"
			(at 205.74 154.94 0)
			(effects
				(font
					(size 1.27 1.27)
					(thickness 0.15)
				)
			)
		)
		(property "Manufacturer" "Murata"
			(at 217.17 170.18 0)
			(effects
				(font
					(size 1.27 1.27)
					(thickness 0.15)
				)
				(justify left bottom)
				(hide yes)
			)
		)
		(property "MPN" "DFE18SBN1R0ME0L"
			(at 217.17 172.72 0)
			(effects
				(font
					(size 1.27 1.27)
					(thickness 0.15)
				)
				(justify left bottom)
				(hide yes)
			)
		)
		(property "ISat" "1.9A"
			(at 217.17 173.99 0)
			(effects
				(font
					(size 1.27 1.27)
				)
				(justify left)
				(hide yes)
			)
		)
		(property "IMax" "1.8A"
			(at 217.17 177.8 0)
			(effects
				(font
					(size 1.27 1.27)
					(thickness 0.15)
				)
				(justify left bottom)
				(hide yes)
			)
		)
		(property "Size" "1.6x0.8"
			(at 217.17 180.34 0)
			(effects
				(font
					(size 1.27 1.27)
					(thickness 0.15)
				)
				(justify left bottom)
				(hide yes)
			)
		)
		(property "License" "Apache-2.0"
			(at 217.17 185.42 0)
			(effects
				(font
					(size 1.27 1.27)
					(thickness 0.15)
				)
				(justify left bottom)
				(hide yes)
			)
		)
		(property "Author" "Antmicro"
			(at 217.17 182.88 0)
			(effects
				(font
					(size 1.27 1.27)
					(thickness 0.15)
				)
				(justify left bottom)
				(hide yes)
			)
		)
		(pin "1"
		)
		(pin "2"
		)
		(instances
			(project "thunderbolt-gpu-adapter"
				(path ""
					(reference "L4")
					(unit 1)
				)
			)
		)
	)
	(symbol
		(lib_id "antmicropower:GND")
		(at 111.76 168.91 0)
		(unit 1)
		(exclude_from_sim no)
		(in_bom yes)
		(on_board yes)
		(dnp no)
		(property "Reference" "#PWR090"
			(at 111.76 175.26 0)
			(effects
				(font
					(size 1.27 1.27)
				)
				(hide yes)
			)
		)
		(property "Value" "GND"
			(at 111.76 172.72 0)
			(effects
				(font
					(size 1.27 1.27)
				)
			)
		)
		(property "Footprint" ""
			(at 111.76 168.91 0)
			(effects
				(font
					(size 1.27 1.27)
				)
				(hide yes)
			)
		)
		(property "Datasheet" ""
			(at 111.76 168.91 0)
			(effects
				(font
					(size 1.27 1.27)
				)
				(hide yes)
			)
		)
		(property "Description" ""
			(at 111.76 168.91 0)
			(effects
				(font
					(size 1.27 1.27)
				)
				(hide yes)
			)
		)
		(property "Author" "Antmicro"
			(at 120.65 176.53 0)
			(effects
				(font
					(size 1.27 1.27)
					(thickness 0.15)
				)
				(justify left bottom)
				(hide yes)
			)
		)
		(property "License" "Apache-2.0"
			(at 120.65 179.07 0)
			(effects
				(font
					(size 1.27 1.27)
					(thickness 0.15)
				)
				(justify left bottom)
				(hide yes)
			)
		)
		(pin "1"
		)
		(instances
			(project "thunderbolt-gpu-adapter"
				(path ""
					(reference "#PWR090")
					(unit 1)
				)
			)
		)
	)
	(symbol
		(lib_id "antmicropower:GND")
		(at 101.6 287.02 0)
		(unit 1)
		(exclude_from_sim no)
		(in_bom yes)
		(on_board yes)
		(dnp no)
		(property "Reference" "#PWR0209"
			(at 101.6 293.37 0)
			(effects
				(font
					(size 1.27 1.27)
				)
				(hide yes)
			)
		)
		(property "Value" "GND"
			(at 101.6 290.83 0)
			(effects
				(font
					(size 1.27 1.27)
				)
			)
		)
		(property "Footprint" ""
			(at 101.6 287.02 0)
			(effects
				(font
					(size 1.27 1.27)
				)
				(hide yes)
			)
		)
		(property "Datasheet" ""
			(at 101.6 287.02 0)
			(effects
				(font
					(size 1.27 1.27)
				)
				(hide yes)
			)
		)
		(property "Description" ""
			(at 101.6 287.02 0)
			(effects
				(font
					(size 1.27 1.27)
				)
				(hide yes)
			)
		)
		(property "Author" "Antmicro"
			(at 110.49 294.64 0)
			(effects
				(font
					(size 1.27 1.27)
					(thickness 0.15)
				)
				(justify left bottom)
				(hide yes)
			)
		)
		(property "License" "Apache-2.0"
			(at 110.49 297.18 0)
			(effects
				(font
					(size 1.27 1.27)
					(thickness 0.15)
				)
				(justify left bottom)
				(hide yes)
			)
		)
		(pin "1"
		)
		(instances
			(project "thunderbolt-gpu-adapter"
				(path ""
					(reference "#PWR0209")
					(unit 1)
				)
			)
		)
	)
	(symbol
		(lib_id "antmicroCapacitors0402:C_1u_0402")
		(at 193.04 182.88 90)
		(unit 1)
		(exclude_from_sim no)
		(in_bom yes)
		(on_board yes)
		(dnp no)
		(property "Reference" "C81"
			(at 193.675 178.435 90)
			(effects
				(font
					(size 1.27 1.27)
					(thickness 0.15)
				)
				(justify right)
			)
		)
		(property "Value" "C_1u_0402"
			(at 203.2 162.56 0)
			(effects
				(font
					(size 1.27 1.27)
					(thickness 0.15)
				)
				(justify left bottom)
				(hide yes)
			)
		)
		(property "Footprint" "antmicro-footprints:C_0402_1005Metric"
			(at 205.74 162.56 0)
			(effects
				(font
					(size 1.27 1.27)
					(thickness 0.15)
				)
				(justify left bottom)
				(hide yes)
			)
		)
		(property "Datasheet" "https://product.tdk.com/en/search/capacitor/ceramic/mlcc/info?part_no=C1005X6S1A105K050BC"
			(at 208.28 162.56 0)
			(effects
				(font
					(size 1.27 1.27)
					(thickness 0.15)
				)
				(justify left bottom)
				(hide yes)
			)
		)
		(property "Description" ""
			(at 193.04 182.88 0)
			(effects
				(font
					(size 1.27 1.27)
				)
				(hide yes)
			)
		)
		(property "MPN" "C1005X6S1A105K050BC"
			(at 210.82 162.56 0)
			(effects
				(font
					(size 1.27 1.27)
					(thickness 0.15)
				)
				(justify left bottom)
				(hide yes)
			)
		)
		(property "Manufacturer" "TDK"
			(at 213.36 162.56 0)
			(effects
				(font
					(size 1.27 1.27)
					(thickness 0.15)
				)
				(justify left bottom)
				(hide yes)
			)
		)
		(property "License" "Apache-2.0"
			(at 215.9 162.56 0)
			(effects
				(font
					(size 1.27 1.27)
					(thickness 0.15)
				)
				(justify left bottom)
				(hide yes)
			)
		)
		(property "Val" "1u"
			(at 193.675 182.245 90)
			(effects
				(font
					(size 1.27 1.27)
					(thickness 0.15)
				)
				(justify right)
			)
		)
		(property "Voltage" ""
			(at 220.98 162.56 0)
			(effects
				(font
					(size 1.27 1.27)
				)
				(justify left bottom)
				(hide yes)
			)
		)
		(property "Dielectric" ""
			(at 223.52 162.56 0)
			(effects
				(font
					(size 1.27 1.27)
				)
				(justify left bottom)
				(hide yes)
			)
		)
		(property "Author" "Antmicro"
			(at 218.44 162.56 0)
			(effects
				(font
					(size 1.27 1.27)
					(thickness 0.15)
				)
				(justify left bottom)
				(hide yes)
			)
		)
		(pin "1"
		)
		(pin "2"
		)
		(instances
			(project "thunderbolt-gpu-adapter"
				(path ""
					(reference "C81")
					(unit 1)
				)
			)
		)
	)
	(symbol
		(lib_id "antmicroCapacitors0603:C_22u_0603")
		(at 186.69 201.93 90)
		(unit 1)
		(exclude_from_sim no)
		(in_bom yes)
		(on_board yes)
		(dnp no)
		(property "Reference" "C79"
			(at 187.325 197.485 90)
			(effects
				(font
					(size 1.27 1.27)
					(thickness 0.15)
				)
				(justify right)
			)
		)
		(property "Value" "C_22u_0603"
			(at 196.85 181.61 0)
			(effects
				(font
					(size 1.27 1.27)
					(thickness 0.15)
				)
				(justify left bottom)
				(hide yes)
			)
		)
		(property "Footprint" "antmicro-footprints:C_0603_1608Metric"
			(at 199.39 181.61 0)
			(effects
				(font
					(size 1.27 1.27)
					(thickness 0.15)
				)
				(justify left bottom)
				(hide yes)
			)
		)
		(property "Datasheet" "https://www.murata.com/products/productdetail?partno=GRM188R60J226MEA0%23"
			(at 201.93 181.61 0)
			(effects
				(font
					(size 1.27 1.27)
					(thickness 0.15)
				)
				(justify left bottom)
				(hide yes)
			)
		)
		(property "Description" ""
			(at 186.69 201.93 0)
			(effects
				(font
					(size 1.27 1.27)
				)
				(hide yes)
			)
		)
		(property "MPN" "GRM188R60J226MEA0D"
			(at 204.47 181.61 0)
			(effects
				(font
					(size 1.27 1.27)
					(thickness 0.15)
				)
				(justify left bottom)
				(hide yes)
			)
		)
		(property "Manufacturer" "Murata"
			(at 207.01 181.61 0)
			(effects
				(font
					(size 1.27 1.27)
					(thickness 0.15)
				)
				(justify left bottom)
				(hide yes)
			)
		)
		(property "License" "Apache-2.0"
			(at 209.55 181.61 0)
			(effects
				(font
					(size 1.27 1.27)
					(thickness 0.15)
				)
				(justify left bottom)
				(hide yes)
			)
		)
		(property "Val" "22u"
			(at 187.325 201.295 90)
			(effects
				(font
					(size 1.27 1.27)
					(thickness 0.15)
				)
				(justify right)
			)
		)
		(property "Voltage" ""
			(at 214.63 181.61 0)
			(effects
				(font
					(size 1.27 1.27)
				)
				(justify left bottom)
				(hide yes)
			)
		)
		(property "Dielectric" ""
			(at 217.17 181.61 0)
			(effects
				(font
					(size 1.27 1.27)
				)
				(justify left bottom)
				(hide yes)
			)
		)
		(property "Author" "Antmicro"
			(at 212.09 181.61 0)
			(effects
				(font
					(size 1.27 1.27)
					(thickness 0.15)
				)
				(justify left bottom)
				(hide yes)
			)
		)
		(pin "1"
		)
		(pin "2"
		)
		(instances
			(project "thunderbolt-gpu-adapter"
				(path ""
					(reference "C79")
					(unit 1)
				)
			)
		)
	)
	(symbol
		(lib_id "antmicroCapacitors0402:C_10u_0402")
		(at 205.74 222.25 90)
		(unit 1)
		(exclude_from_sim no)
		(in_bom yes)
		(on_board yes)
		(dnp no)
		(fields_autoplaced yes)
		(property "Reference" "C78"
			(at 206.375 217.805 90)
			(effects
				(font
					(size 1.27 1.27)
					(thickness 0.15)
				)
				(justify right)
			)
		)
		(property "Value" "C_10u_0402"
			(at 215.9 201.93 0)
			(effects
				(font
					(size 1.27 1.27)
					(thickness 0.15)
				)
				(justify left bottom)
				(hide yes)
			)
		)
		(property "Footprint" "antmicro-footprints:C_0402_1005Metric"
			(at 218.44 201.93 0)
			(effects
				(font
					(size 1.27 1.27)
					(thickness 0.15)
				)
				(justify left bottom)
				(hide yes)
			)
		)
		(property "Datasheet" "https://www.yageo.com/en/Chart/Download/pdf/CC0402MRX5R5BB106"
			(at 220.98 201.93 0)
			(effects
				(font
					(size 1.27 1.27)
					(thickness 0.15)
				)
				(justify left bottom)
				(hide yes)
			)
		)
		(property "Description" ""
			(at 205.74 222.25 0)
			(effects
				(font
					(size 1.27 1.27)
				)
				(hide yes)
			)
		)
		(property "MPN" "CC0402MRX5R5BB106"
			(at 223.52 201.93 0)
			(effects
				(font
					(size 1.27 1.27)
					(thickness 0.15)
				)
				(justify left bottom)
				(hide yes)
			)
		)
		(property "Manufacturer" "YAGEO"
			(at 226.06 201.93 0)
			(effects
				(font
					(size 1.27 1.27)
					(thickness 0.15)
				)
				(justify left bottom)
				(hide yes)
			)
		)
		(property "License" "Apache-2.0"
			(at 228.6 201.93 0)
			(effects
				(font
					(size 1.27 1.27)
					(thickness 0.15)
				)
				(justify left bottom)
				(hide yes)
			)
		)
		(property "Val" "10u"
			(at 206.375 221.615 90)
			(effects
				(font
					(size 1.27 1.27)
					(thickness 0.15)
				)
				(justify right)
			)
		)
		(property "Voltage" ""
			(at 233.68 201.93 0)
			(effects
				(font
					(size 1.27 1.27)
				)
				(justify left bottom)
				(hide yes)
			)
		)
		(property "Dielectric" ""
			(at 236.22 201.93 0)
			(effects
				(font
					(size 1.27 1.27)
				)
				(justify left bottom)
				(hide yes)
			)
		)
		(property "Author" "Antmicro"
			(at 231.14 201.93 0)
			(effects
				(font
					(size 1.27 1.27)
					(thickness 0.15)
				)
				(justify left bottom)
				(hide yes)
			)
		)
		(pin "1"
		)
		(pin "2"
		)
		(instances
			(project "thunderbolt-gpu-adapter"
				(path ""
					(reference "C78")
					(unit 1)
				)
			)
		)
	)
	(symbol
		(lib_id "antmicropower:GND")
		(at 217.17 292.1 0)
		(unit 1)
		(exclude_from_sim no)
		(in_bom yes)
		(on_board yes)
		(dnp no)
		(property "Reference" "#PWR0126"
			(at 217.17 298.45 0)
			(effects
				(font
					(size 1.27 1.27)
				)
				(hide yes)
			)
		)
		(property "Value" "GND"
			(at 217.17 295.91 0)
			(effects
				(font
					(size 1.27 1.27)
				)
			)
		)
		(property "Footprint" ""
			(at 217.17 292.1 0)
			(effects
				(font
					(size 1.27 1.27)
				)
				(hide yes)
			)
		)
		(property "Datasheet" ""
			(at 217.17 292.1 0)
			(effects
				(font
					(size 1.27 1.27)
				)
				(hide yes)
			)
		)
		(property "Description" ""
			(at 217.17 292.1 0)
			(effects
				(font
					(size 1.27 1.27)
				)
				(hide yes)
			)
		)
		(property "Author" "Antmicro"
			(at 226.06 299.72 0)
			(effects
				(font
					(size 1.27 1.27)
					(thickness 0.15)
				)
				(justify left bottom)
				(hide yes)
			)
		)
		(property "License" "Apache-2.0"
			(at 226.06 302.26 0)
			(effects
				(font
					(size 1.27 1.27)
					(thickness 0.15)
				)
				(justify left bottom)
				(hide yes)
			)
		)
		(pin "1"
		)
		(instances
			(project "thunderbolt-gpu-adapter"
				(path ""
					(reference "#PWR0126")
					(unit 1)
				)
			)
		)
	)
	(symbol
		(lib_id "antmicropower:GND")
		(at 193.04 224.79 0)
		(unit 1)
		(exclude_from_sim no)
		(in_bom yes)
		(on_board yes)
		(dnp no)
		(property "Reference" "#PWR0118"
			(at 193.04 231.14 0)
			(effects
				(font
					(size 1.27 1.27)
				)
				(hide yes)
			)
		)
		(property "Value" "GND"
			(at 193.04 228.6 0)
			(effects
				(font
					(size 1.27 1.27)
				)
			)
		)
		(property "Footprint" ""
			(at 193.04 224.79 0)
			(effects
				(font
					(size 1.27 1.27)
				)
				(hide yes)
			)
		)
		(property "Datasheet" ""
			(at 193.04 224.79 0)
			(effects
				(font
					(size 1.27 1.27)
				)
				(hide yes)
			)
		)
		(property "Description" ""
			(at 193.04 224.79 0)
			(effects
				(font
					(size 1.27 1.27)
				)
				(hide yes)
			)
		)
		(property "Author" "Antmicro"
			(at 201.93 232.41 0)
			(effects
				(font
					(size 1.27 1.27)
					(thickness 0.15)
				)
				(justify left bottom)
				(hide yes)
			)
		)
		(property "License" "Apache-2.0"
			(at 201.93 234.95 0)
			(effects
				(font
					(size 1.27 1.27)
					(thickness 0.15)
				)
				(justify left bottom)
				(hide yes)
			)
		)
		(pin "1"
		)
		(instances
			(project "thunderbolt-gpu-adapter"
				(path ""
					(reference "#PWR0118")
					(unit 1)
				)
			)
		)
	)
	(symbol
		(lib_id "antmicropower:GND")
		(at 93.98 168.91 0)
		(unit 1)
		(exclude_from_sim no)
		(in_bom yes)
		(on_board yes)
		(dnp no)
		(property "Reference" "#PWR081"
			(at 93.98 175.26 0)
			(effects
				(font
					(size 1.27 1.27)
				)
				(hide yes)
			)
		)
		(property "Value" "GND"
			(at 93.98 172.72 0)
			(effects
				(font
					(size 1.27 1.27)
				)
			)
		)
		(property "Footprint" ""
			(at 93.98 168.91 0)
			(effects
				(font
					(size 1.27 1.27)
				)
				(hide yes)
			)
		)
		(property "Datasheet" ""
			(at 93.98 168.91 0)
			(effects
				(font
					(size 1.27 1.27)
				)
				(hide yes)
			)
		)
		(property "Description" ""
			(at 93.98 168.91 0)
			(effects
				(font
					(size 1.27 1.27)
				)
				(hide yes)
			)
		)
		(property "Author" "Antmicro"
			(at 102.87 176.53 0)
			(effects
				(font
					(size 1.27 1.27)
					(thickness 0.15)
				)
				(justify left bottom)
				(hide yes)
			)
		)
		(property "License" "Apache-2.0"
			(at 102.87 179.07 0)
			(effects
				(font
					(size 1.27 1.27)
					(thickness 0.15)
				)
				(justify left bottom)
				(hide yes)
			)
		)
		(pin "1"
		)
		(instances
			(project "thunderbolt-gpu-adapter"
				(path ""
					(reference "#PWR081")
					(unit 1)
				)
			)
		)
	)
	(symbol
		(lib_id "antmicroOperationalAmplifiers:MCP6541_SOT23-5")
		(at 124.46 280.67 0)
		(unit 2)
		(exclude_from_sim no)
		(in_bom yes)
		(on_board yes)
		(dnp no)
		(fields_autoplaced yes)
		(property "Reference" "U13"
			(at 133.35 280.67 0)
			(effects
				(font
					(size 1.27 1.27)
					(thickness 0.15)
				)
				(justify left)
			)
		)
		(property "Value" "MCP6541_SOT23-5"
			(at 149.86 290.83 0)
			(effects
				(font
					(size 1.27 1.27)
					(thickness 0.15)
				)
				(justify left bottom)
				(hide yes)
			)
		)
		(property "Footprint" "antmicro-footprints:SOT-23-5"
			(at 149.86 293.37 0)
			(effects
				(font
					(size 1.27 1.27)
					(thickness 0.15)
				)
				(justify left bottom)
				(hide yes)
			)
		)
		(property "Datasheet" "https://www.farnell.com/datasheets/1641674.pdf"
			(at 149.86 295.91 0)
			(effects
				(font
					(size 1.27 1.27)
					(thickness 0.15)
				)
				(justify left bottom)
				(hide yes)
			)
		)
		(property "Description" ""
			(at 124.46 280.67 0)
			(effects
				(font
					(size 1.27 1.27)
				)
				(hide yes)
			)
		)
		(property "MPN" "MCP6541T-E/OT"
			(at 133.35 283.21 0)
			(effects
				(font
					(size 1.27 1.27)
					(thickness 0.15)
				)
				(justify left)
			)
		)
		(property "Manufacturer" "Microchip Technology"
			(at 149.86 298.45 0)
			(effects
				(font
					(size 1.27 1.27)
					(thickness 0.15)
				)
				(justify left bottom)
				(hide yes)
			)
		)
		(property "Author" "Antmicro"
			(at 149.86 300.99 0)
			(effects
				(font
					(size 1.27 1.27)
					(thickness 0.15)
				)
				(justify left bottom)
				(hide yes)
			)
		)
		(property "License" "Apache-2.0"
			(at 149.86 303.53 0)
			(effects
				(font
					(size 1.27 1.27)
					(thickness 0.15)
				)
				(justify left bottom)
				(hide yes)
			)
		)
		(pin "1"
		)
		(pin "3"
		)
		(pin "4"
		)
		(pin "2"
		)
		(pin "5"
		)
		(instances
			(project "thunderbolt-gpu-adapter"
				(path ""
					(reference "U13")
					(unit 2)
				)
			)
		)
	)
	(symbol
		(lib_id "antmicropower:GND")
		(at 224.79 134.62 0)
		(unit 1)
		(exclude_from_sim no)
		(in_bom yes)
		(on_board yes)
		(dnp no)
		(property "Reference" "#PWR0104"
			(at 224.79 140.97 0)
			(effects
				(font
					(size 1.27 1.27)
				)
				(hide yes)
			)
		)
		(property "Value" "GND"
			(at 224.79 138.43 0)
			(effects
				(font
					(size 1.27 1.27)
				)
			)
		)
		(property "Footprint" ""
			(at 224.79 134.62 0)
			(effects
				(font
					(size 1.27 1.27)
				)
				(hide yes)
			)
		)
		(property "Datasheet" ""
			(at 224.79 134.62 0)
			(effects
				(font
					(size 1.27 1.27)
				)
				(hide yes)
			)
		)
		(property "Description" ""
			(at 224.79 134.62 0)
			(effects
				(font
					(size 1.27 1.27)
				)
				(hide yes)
			)
		)
		(property "Author" "Antmicro"
			(at 233.68 142.24 0)
			(effects
				(font
					(size 1.27 1.27)
					(thickness 0.15)
				)
				(justify left bottom)
				(hide yes)
			)
		)
		(property "License" "Apache-2.0"
			(at 233.68 144.78 0)
			(effects
				(font
					(size 1.27 1.27)
					(thickness 0.15)
				)
				(justify left bottom)
				(hide yes)
			)
		)
		(pin "1"
		)
		(instances
			(project "thunderbolt-gpu-adapter"
				(path ""
					(reference "#PWR0104")
					(unit 1)
				)
			)
		)
	)
	(symbol
		(lib_id "antmicropower:GND")
		(at 116.84 203.2 0)
		(unit 1)
		(exclude_from_sim no)
		(in_bom yes)
		(on_board yes)
		(dnp no)
		(property "Reference" "#PWR088"
			(at 116.84 209.55 0)
			(effects
				(font
					(size 1.27 1.27)
				)
				(hide yes)
			)
		)
		(property "Value" "GND"
			(at 116.84 207.01 0)
			(effects
				(font
					(size 1.27 1.27)
				)
			)
		)
		(property "Footprint" ""
			(at 116.84 203.2 0)
			(effects
				(font
					(size 1.27 1.27)
				)
				(hide yes)
			)
		)
		(property "Datasheet" ""
			(at 116.84 203.2 0)
			(effects
				(font
					(size 1.27 1.27)
				)
				(hide yes)
			)
		)
		(property "Description" ""
			(at 116.84 203.2 0)
			(effects
				(font
					(size 1.27 1.27)
				)
				(hide yes)
			)
		)
		(property "Author" "Antmicro"
			(at 125.73 210.82 0)
			(effects
				(font
					(size 1.27 1.27)
					(thickness 0.15)
				)
				(justify left bottom)
				(hide yes)
			)
		)
		(property "License" "Apache-2.0"
			(at 125.73 213.36 0)
			(effects
				(font
					(size 1.27 1.27)
					(thickness 0.15)
				)
				(justify left bottom)
				(hide yes)
			)
		)
		(pin "1"
		)
		(instances
			(project "thunderbolt-gpu-adapter"
				(path ""
					(reference "#PWR088")
					(unit 1)
				)
			)
		)
	)
	(symbol
		(lib_id "antmicroInterfaceControllers:JHL6340SLLSQ")
		(at 121.92 139.7 0)
		(unit 1)
		(exclude_from_sim no)
		(in_bom yes)
		(on_board yes)
		(dnp no)
		(fields_autoplaced yes)
		(property "Reference" "U4"
			(at 149.225 131.445 0)
			(effects
				(font
					(size 1.27 1.27)
					(thickness 0.15)
				)
			)
		)
		(property "Value" "JHL6340SLLSQ"
			(at 193.04 142.24 0)
			(effects
				(font
					(size 1.27 1.27)
					(thickness 0.15)
				)
				(justify left bottom)
				(hide yes)
			)
		)
		(property "Footprint" "antmicro-footprints:JHL6340SLLSQ"
			(at 193.04 144.78 0)
			(effects
				(font
					(size 1.27 1.27)
					(thickness 0.15)
				)
				(justify left bottom)
				(hide yes)
			)
		)
		(property "Datasheet" "https://www.thunderbolttechnology.net/sites/default/files/18-241_ThunderboltController_Brief_HI.pdf"
			(at 193.04 147.32 0)
			(effects
				(font
					(size 1.27 1.27)
					(thickness 0.15)
				)
				(justify left bottom)
				(hide yes)
			)
		)
		(property "Description" ""
			(at 121.92 139.7 0)
			(effects
				(font
					(size 1.27 1.27)
				)
				(hide yes)
			)
		)
		(property "Manufacturer" "Intel"
			(at 193.04 149.86 0)
			(effects
				(font
					(size 1.27 1.27)
					(thickness 0.15)
				)
				(justify left bottom)
				(hide yes)
			)
		)
		(property "MPN" "JHL6340SLLSQ"
			(at 149.225 133.985 0)
			(effects
				(font
					(size 1.27 1.27)
					(thickness 0.15)
				)
			)
		)
		(property "Author" "Antmicro"
			(at 193.04 154.94 0)
			(effects
				(font
					(size 1.27 1.27)
					(thickness 0.15)
				)
				(justify left bottom)
				(hide yes)
			)
		)
		(property "License" "Apache-2.0"
			(at 193.04 157.48 0)
			(effects
				(font
					(size 1.27 1.27)
					(thickness 0.15)
				)
				(justify left bottom)
				(hide yes)
			)
		)
		(pin "V5"
		)
		(pin "Y9"
		)
		(pin "AC5"
		)
		(pin "F12"
		)
		(pin "L13"
		)
		(pin "A13"
		)
		(pin "T23"
		)
		(pin "AA2"
		)
		(pin "L22"
		)
		(pin "R16"
		)
		(pin "N13"
		)
		(pin "D9"
		)
		(pin "T2"
		)
		(pin "R12"
		)
		(pin "U1"
		)
		(pin "R23"
		)
		(pin "J23"
		)
		(pin "T22"
		)
		(pin "L23"
		)
		(pin "B3"
		)
		(pin "V4"
		)
		(pin "N8"
		)
		(pin "AB11"
		)
		(pin "AB4"
		)
		(pin "M6"
		)
		(pin "K22"
		)
		(pin "R5"
		)
		(pin "L15"
		)
		(pin "F13"
		)
		(pin "L12"
		)
		(pin "H20"
		)
		(pin "V15"
		)
		(pin "V22"
		)
		(pin "V19"
		)
		(pin "P23"
		)
		(pin "M18"
		)
		(pin "A4"
		)
		(pin "A9"
		)
		(pin "M23"
		)
		(pin "Y8"
		)
		(pin "Y4"
		)
		(pin "N5"
		)
		(pin "T5"
		)
		(pin "W1"
		)
		(pin "Y11"
		)
		(pin "Y5"
		)
		(pin "B22"
		)
		(pin "B6"
		)
		(pin "V8"
		)
		(pin "V1"
		)
		(pin "A17"
		)
		(pin "Y2"
		)
		(pin "W2"
		)
		(pin "R22"
		)
		(pin "N6"
		)
		(pin "F16"
		)
		(pin "AB13"
		)
		(pin "H4"
		)
		(pin "F22"
		)
		(pin "R4"
		)
		(pin "F23"
		)
		(pin "W11"
		)
		(pin "D13"
		)
		(pin "AC10"
		)
		(pin "M9"
		)
		(pin "V2"
		)
		(pin "L19"
		)
		(pin "T18"
		)
		(pin "L20"
		)
		(pin "H8"
		)
		(pin "AB7"
		)
		(pin "Y23"
		)
		(pin "K1"
		)
		(pin "AC7"
		)
		(pin "H18"
		)
		(pin "C1"
		)
		(pin "N1"
		)
		(pin "AB5"
		)
		(pin "J5"
		)
		(pin "R15"
		)
		(pin "M13"
		)
		(pin "D1"
		)
		(pin "E20"
		)
		(pin "AC11"
		)
		(pin "A5"
		)
		(pin "AB15"
		)
		(pin "L8"
		)
		(pin "D6"
		)
		(pin "D19"
		)
		(pin "V6"
		)
		(pin "N19"
		)
		(pin "T11"
		)
		(pin "W8"
		)
		(pin "C22"
		)
		(pin "H19"
		)
		(pin "L11"
		)
		(pin "AC13"
		)
		(pin "D2"
		)
		(pin "K23"
		)
		(pin "L2"
		)
		(pin "A7"
		)
		(pin "H16"
		)
		(pin "Y16"
		)
		(pin "V12"
		)
		(pin "AB9"
		)
		(pin "M20"
		)
		(pin "N20"
		)
		(pin "R19"
		)
		(pin "U22"
		)
		(pin "AB21"
		)
		(pin "E4"
		)
		(pin "R6"
		)
		(pin "R20"
		)
		(pin "AC1"
		)
		(pin "G2"
		)
		(pin "M8"
		)
		(pin "M16"
		)
		(pin "V20"
		)
		(pin "F18"
		)
		(pin "AB3"
		)
		(pin "AA1"
		)
		(pin "D22"
		)
		(pin "V11"
		)
		(pin "T1"
		)
		(pin "V18"
		)
		(pin "B9"
		)
		(pin "J9"
		)
		(pin "M5"
		)
		(pin "H15"
		)
		(pin "M12"
		)
		(pin "M15"
		)
		(pin "AC9"
		)
		(pin "W23"
		)
		(pin "V9"
		)
		(pin "B8"
		)
		(pin "N16"
		)
		(pin "B14"
		)
		(pin "AC23"
		)
		(pin "W18"
		)
		(pin "M1"
		)
		(pin "N15"
		)
		(pin "AB17"
		)
		(pin "U23"
		)
		(pin "Y22"
		)
		(pin "L9"
		)
		(pin "T13"
		)
		(pin "F11"
		)
		(pin "N4"
		)
		(pin "F19"
		)
		(pin "W6"
		)
		(pin "F15"
		)
		(pin "B7"
		)
		(pin "Y1"
		)
		(pin "A6"
		)
		(pin "B2"
		)
		(pin "B4"
		)
		(pin "R13"
		)
		(pin "K2"
		)
		(pin "N18"
		)
		(pin "B13"
		)
		(pin "T19"
		)
		(pin "W22"
		)
		(pin "H23"
		)
		(pin "T4"
		)
		(pin "L18"
		)
		(pin "E19"
		)
		(pin "H2"
		)
		(pin "L1"
		)
		(pin "F20"
		)
		(pin "B23"
		)
		(pin "R8"
		)
		(pin "M22"
		)
		(pin "F2"
		)
		(pin "E18"
		)
		(pin "R2"
		)
		(pin "W4"
		)
		(pin "B5"
		)
		(pin "W19"
		)
		(pin "N22"
		)
		(pin "D5"
		)
		(pin "W20"
		)
		(pin "W12"
		)
		(pin "B11"
		)
		(pin "R11"
		)
		(pin "E2"
		)
		(pin "D18"
		)
		(pin "T8"
		)
		(pin "L5"
		)
		(pin "M4"
		)
		(pin "T20"
		)
		(pin "A3"
		)
		(pin "AC3"
		)
		(pin "A19"
		)
		(pin "L16"
		)
		(pin "F4"
		)
		(pin "T12"
		)
		(pin "Y18"
		)
		(pin "T16"
		)
		(pin "AB19"
		)
		(pin "B12"
		)
		(pin "E23"
		)
		(pin "E1"
		)
		(pin "T6"
		)
		(pin "Y19"
		)
		(pin "T15"
		)
		(pin "P22"
		)
		(pin "AB16"
		)
		(pin "AC4"
		)
		(pin "D15"
		)
		(pin "G1"
		)
		(pin "A8"
		)
		(pin "Y12"
		)
		(pin "J4"
		)
		(pin "J1"
		)
		(pin "E22"
		)
		(pin "D20"
		)
		(pin "M2"
		)
		(pin "V23"
		)
		(pin "AB10"
		)
		(pin "AB2"
		)
		(pin "AC15"
		)
		(pin "D23"
		)
		(pin "A23"
		)
		(pin "C23"
		)
		(pin "J2"
		)
		(pin "A21"
		)
		(pin "F1"
		)
		(pin "H5"
		)
		(pin "N11"
		)
		(pin "B20"
		)
		(pin "H22"
		)
		(pin "AA23"
		)
		(pin "E13"
		)
		(pin "J12"
		)
		(pin "W9"
		)
		(pin "H9"
		)
		(pin "B19"
		)
		(pin "AB8"
		)
		(pin "AB22"
		)
		(pin "AB6"
		)
		(pin "AB20"
		)
		(pin "AC2"
		)
		(pin "E9"
		)
		(pin "J11"
		)
		(pin "L4"
		)
		(pin "J8"
		)
		(pin "AC22"
		)
		(pin "J13"
		)
		(pin "N12"
		)
		(pin "J15"
		)
		(pin "B18"
		)
		(pin "Y15"
		)
		(pin "U2"
		)
		(pin "AC12"
		)
		(pin "D16"
		)
		(pin "AB14"
		)
		(pin "AC6"
		)
		(pin "A14"
		)
		(pin "V13"
		)
		(pin "G22"
		)
		(pin "Y13"
		)
		(pin "B16"
		)
		(pin "AB18"
		)
		(pin "B17"
		)
		(pin "A20"
		)
		(pin "AB12"
		)
		(pin "R1"
		)
		(pin "AC20"
		)
		(pin "H12"
		)
		(pin "A2"
		)
		(pin "F5"
		)
		(pin "E6"
		)
		(pin "A10"
		)
		(pin "A12"
		)
		(pin "H11"
		)
		(pin "F9"
		)
		(pin "A1"
		)
		(pin "AB1"
		)
		(pin "E8"
		)
		(pin "A11"
		)
		(pin "L6"
		)
		(pin "B21"
		)
		(pin "AB23"
		)
		(pin "W13"
		)
		(pin "P2"
		)
		(pin "W16"
		)
		(pin "AC16"
		)
		(pin "H6"
		)
		(pin "Y6"
		)
		(pin "A15"
		)
		(pin "J6"
		)
		(pin "V16"
		)
		(pin "N9"
		)
		(pin "AC21"
		)
		(pin "J19"
		)
		(pin "J20"
		)
		(pin "AC17"
		)
		(pin "AC19"
		)
		(pin "M11"
		)
		(pin "D4"
		)
		(pin "P1"
		)
		(pin "W5"
		)
		(pin "R18"
		)
		(pin "E16"
		)
		(pin "N23"
		)
		(pin "A22"
		)
		(pin "R9"
		)
		(pin "D8"
		)
		(pin "E15"
		)
		(pin "M19"
		)
		(pin "Y20"
		)
		(pin "T9"
		)
		(pin "H13"
		)
		(pin "W15"
		)
		(pin "B10"
		)
		(pin "AC14"
		)
		(pin "AC18"
		)
		(pin "C2"
		)
		(pin "E5"
		)
		(pin "J22"
		)
		(pin "J18"
		)
		(pin "J16"
		)
		(pin "AC8"
		)
		(pin "B1"
		)
		(pin "N2"
		)
		(pin "E11"
		)
		(pin "A18"
		)
		(pin "H1"
		)
		(pin "G23"
		)
		(pin "A16"
		)
		(pin "D11"
		)
		(pin "B15"
		)
		(pin "F8"
		)
		(pin "E12"
		)
		(pin "AA22"
		)
		(pin "D12"
		)
		(pin "F6"
		)
		(instances
			(project "thunderbolt-gpu-adapter"
				(path ""
					(reference "U4")
					(unit 1)
				)
			)
		)
	)
	(symbol
		(lib_id "antmicropower:GND")
		(at 193.04 184.15 0)
		(unit 1)
		(exclude_from_sim no)
		(in_bom yes)
		(on_board yes)
		(dnp no)
		(property "Reference" "#PWR0109"
			(at 193.04 190.5 0)
			(effects
				(font
					(size 1.27 1.27)
				)
				(hide yes)
			)
		)
		(property "Value" "GND"
			(at 193.04 187.96 0)
			(effects
				(font
					(size 1.27 1.27)
				)
			)
		)
		(property "Footprint" ""
			(at 193.04 184.15 0)
			(effects
				(font
					(size 1.27 1.27)
				)
				(hide yes)
			)
		)
		(property "Datasheet" ""
			(at 193.04 184.15 0)
			(effects
				(font
					(size 1.27 1.27)
				)
				(hide yes)
			)
		)
		(property "Description" ""
			(at 193.04 184.15 0)
			(effects
				(font
					(size 1.27 1.27)
				)
				(hide yes)
			)
		)
		(property "Author" "Antmicro"
			(at 201.93 191.77 0)
			(effects
				(font
					(size 1.27 1.27)
					(thickness 0.15)
				)
				(justify left bottom)
				(hide yes)
			)
		)
		(property "License" "Apache-2.0"
			(at 201.93 194.31 0)
			(effects
				(font
					(size 1.27 1.27)
					(thickness 0.15)
				)
				(justify left bottom)
				(hide yes)
			)
		)
		(pin "1"
		)
		(instances
			(project "thunderbolt-gpu-adapter"
				(path ""
					(reference "#PWR0109")
					(unit 1)
				)
			)
		)
	)
	(symbol
		(lib_id "antmicropower:GND")
		(at 205.74 224.79 0)
		(unit 1)
		(exclude_from_sim no)
		(in_bom yes)
		(on_board yes)
		(dnp no)
		(property "Reference" "#PWR0106"
			(at 205.74 231.14 0)
			(effects
				(font
					(size 1.27 1.27)
				)
				(hide yes)
			)
		)
		(property "Value" "GND"
			(at 205.74 228.6 0)
			(effects
				(font
					(size 1.27 1.27)
				)
			)
		)
		(property "Footprint" ""
			(at 205.74 224.79 0)
			(effects
				(font
					(size 1.27 1.27)
				)
				(hide yes)
			)
		)
		(property "Datasheet" ""
			(at 205.74 224.79 0)
			(effects
				(font
					(size 1.27 1.27)
				)
				(hide yes)
			)
		)
		(property "Description" ""
			(at 205.74 224.79 0)
			(effects
				(font
					(size 1.27 1.27)
				)
				(hide yes)
			)
		)
		(property "Author" "Antmicro"
			(at 214.63 232.41 0)
			(effects
				(font
					(size 1.27 1.27)
					(thickness 0.15)
				)
				(justify left bottom)
				(hide yes)
			)
		)
		(property "License" "Apache-2.0"
			(at 214.63 234.95 0)
			(effects
				(font
					(size 1.27 1.27)
					(thickness 0.15)
				)
				(justify left bottom)
				(hide yes)
			)
		)
		(pin "1"
		)
		(instances
			(project "thunderbolt-gpu-adapter"
				(path ""
					(reference "#PWR0106")
					(unit 1)
				)
			)
		)
	)
	(symbol
		(lib_id "antmicropower:GND")
		(at 105.41 168.91 0)
		(unit 1)
		(exclude_from_sim no)
		(in_bom yes)
		(on_board yes)
		(dnp no)
		(property "Reference" "#PWR087"
			(at 105.41 175.26 0)
			(effects
				(font
					(size 1.27 1.27)
				)
				(hide yes)
			)
		)
		(property "Value" "GND"
			(at 105.41 172.72 0)
			(effects
				(font
					(size 1.27 1.27)
				)
			)
		)
		(property "Footprint" ""
			(at 105.41 168.91 0)
			(effects
				(font
					(size 1.27 1.27)
				)
				(hide yes)
			)
		)
		(property "Datasheet" ""
			(at 105.41 168.91 0)
			(effects
				(font
					(size 1.27 1.27)
				)
				(hide yes)
			)
		)
		(property "Description" ""
			(at 105.41 168.91 0)
			(effects
				(font
					(size 1.27 1.27)
				)
				(hide yes)
			)
		)
		(property "Author" "Antmicro"
			(at 114.3 176.53 0)
			(effects
				(font
					(size 1.27 1.27)
					(thickness 0.15)
				)
				(justify left bottom)
				(hide yes)
			)
		)
		(property "License" "Apache-2.0"
			(at 114.3 179.07 0)
			(effects
				(font
					(size 1.27 1.27)
					(thickness 0.15)
				)
				(justify left bottom)
				(hide yes)
			)
		)
		(pin "1"
		)
		(instances
			(project "thunderbolt-gpu-adapter"
				(path ""
					(reference "#PWR087")
					(unit 1)
				)
			)
		)
	)
	(symbol
		(lib_id "antmicropower:GND")
		(at 180.34 184.15 0)
		(unit 1)
		(exclude_from_sim no)
		(in_bom yes)
		(on_board yes)
		(dnp no)
		(property "Reference" "#PWR099"
			(at 180.34 190.5 0)
			(effects
				(font
					(size 1.27 1.27)
				)
				(hide yes)
			)
		)
		(property "Value" "GND"
			(at 180.34 187.96 0)
			(effects
				(font
					(size 1.27 1.27)
				)
			)
		)
		(property "Footprint" ""
			(at 180.34 184.15 0)
			(effects
				(font
					(size 1.27 1.27)
				)
				(hide yes)
			)
		)
		(property "Datasheet" ""
			(at 180.34 184.15 0)
			(effects
				(font
					(size 1.27 1.27)
				)
				(hide yes)
			)
		)
		(property "Description" ""
			(at 180.34 184.15 0)
			(effects
				(font
					(size 1.27 1.27)
				)
				(hide yes)
			)
		)
		(property "Author" "Antmicro"
			(at 189.23 191.77 0)
			(effects
				(font
					(size 1.27 1.27)
					(thickness 0.15)
				)
				(justify left bottom)
				(hide yes)
			)
		)
		(property "License" "Apache-2.0"
			(at 189.23 194.31 0)
			(effects
				(font
					(size 1.27 1.27)
					(thickness 0.15)
				)
				(justify left bottom)
				(hide yes)
			)
		)
		(pin "1"
		)
		(instances
			(project "thunderbolt-gpu-adapter"
				(path ""
					(reference "#PWR099")
					(unit 1)
				)
			)
		)
	)
	(symbol
		(lib_id "antmicroResistors0402:R_1k_0402")
		(at 217.17 222.25 90)
		(unit 1)
		(exclude_from_sim no)
		(in_bom yes)
		(on_board yes)
		(dnp no)
		(fields_autoplaced yes)
		(property "Reference" "R137"
			(at 219.71 218.44 90)
			(effects
				(font
					(size 1.27 1.27)
					(thickness 0.15)
				)
				(justify right)
			)
		)
		(property "Value" "R_1k_0402"
			(at 229.87 201.93 0)
			(effects
				(font
					(size 1.27 1.27)
					(thickness 0.15)
				)
				(justify left bottom)
				(hide yes)
			)
		)
		(property "Footprint" "antmicro-footprints:R_0402_1005Metric"
			(at 232.41 201.93 0)
			(effects
				(font
					(size 1.27 1.27)
					(thickness 0.15)
				)
				(justify left bottom)
				(hide yes)
			)
		)
		(property "Datasheet" "https://www.bourns.com/docs/product-datasheets/cr.pdf"
			(at 234.95 201.93 0)
			(effects
				(font
					(size 1.27 1.27)
					(thickness 0.15)
				)
				(justify left bottom)
				(hide yes)
			)
		)
		(property "Description" ""
			(at 217.17 222.25 0)
			(effects
				(font
					(size 1.27 1.27)
				)
				(hide yes)
			)
		)
		(property "MPN" "CR0402-FX-1001GLF"
			(at 237.49 201.93 0)
			(effects
				(font
					(size 1.27 1.27)
					(thickness 0.15)
				)
				(justify left bottom)
				(hide yes)
			)
		)
		(property "Manufacturer" "Bourns"
			(at 240.03 201.93 0)
			(effects
				(font
					(size 1.27 1.27)
					(thickness 0.15)
				)
				(justify left bottom)
				(hide yes)
			)
		)
		(property "License" "Apache-2.0"
			(at 242.57 201.93 0)
			(effects
				(font
					(size 1.27 1.27)
					(thickness 0.15)
				)
				(justify left bottom)
				(hide yes)
			)
		)
		(property "Author" "Antmicro"
			(at 245.11 201.93 0)
			(effects
				(font
					(size 1.27 1.27)
					(thickness 0.15)
				)
				(justify left bottom)
				(hide yes)
			)
		)
		(property "Val" "1k"
			(at 219.71 220.98 90)
			(effects
				(font
					(size 1.27 1.27)
					(thickness 0.15)
				)
				(justify right)
			)
		)
		(property "Tolerance" "1%"
			(at 227.33 201.93 0)
			(effects
				(font
					(size 1.27 1.27)
				)
				(justify left bottom)
				(hide yes)
			)
		)
		(pin "1"
		)
		(pin "2"
		)
		(instances
			(project "thunderbolt-gpu-adapter"
				(path ""
					(reference "R137")
					(unit 1)
				)
			)
		)
	)
	(symbol
		(lib_id "antmicropower:GND")
		(at 193.04 203.2 0)
		(unit 1)
		(exclude_from_sim no)
		(in_bom yes)
		(on_board yes)
		(dnp no)
		(property "Reference" "#PWR0110"
			(at 193.04 209.55 0)
			(effects
				(font
					(size 1.27 1.27)
				)
				(hide yes)
			)
		)
		(property "Value" "GND"
			(at 193.04 207.01 0)
			(effects
				(font
					(size 1.27 1.27)
				)
			)
		)
		(property "Footprint" ""
			(at 193.04 203.2 0)
			(effects
				(font
					(size 1.27 1.27)
				)
				(hide yes)
			)
		)
		(property "Datasheet" ""
			(at 193.04 203.2 0)
			(effects
				(font
					(size 1.27 1.27)
				)
				(hide yes)
			)
		)
		(property "Description" ""
			(at 193.04 203.2 0)
			(effects
				(font
					(size 1.27 1.27)
				)
				(hide yes)
			)
		)
		(property "Author" "Antmicro"
			(at 201.93 210.82 0)
			(effects
				(font
					(size 1.27 1.27)
					(thickness 0.15)
				)
				(justify left bottom)
				(hide yes)
			)
		)
		(property "License" "Apache-2.0"
			(at 201.93 213.36 0)
			(effects
				(font
					(size 1.27 1.27)
					(thickness 0.15)
				)
				(justify left bottom)
				(hide yes)
			)
		)
		(pin "1"
		)
		(instances
			(project "thunderbolt-gpu-adapter"
				(path ""
					(reference "#PWR0110")
					(unit 1)
				)
			)
		)
	)
	(symbol
		(lib_id "antmicropower:PWR_FLAG")
		(at 88.9 173.99 0)
		(unit 1)
		(exclude_from_sim no)
		(in_bom yes)
		(on_board yes)
		(dnp no)
		(property "Reference" "#FLG0109"
			(at 88.9 172.085 0)
			(effects
				(font
					(size 1.27 1.27)
				)
				(hide yes)
			)
		)
		(property "Value" "PWR_FLAG"
			(at 97.79 176.53 0)
			(effects
				(font
					(size 1.27 1.27)
				)
				(justify right)
			)
		)
		(property "Footprint" ""
			(at 88.9 173.99 0)
			(effects
				(font
					(size 1.27 1.27)
				)
				(hide yes)
			)
		)
		(property "Datasheet" ""
			(at 88.9 173.99 0)
			(effects
				(font
					(size 1.27 1.27)
				)
				(hide yes)
			)
		)
		(property "Description" ""
			(at 88.9 173.99 0)
			(effects
				(font
					(size 1.27 1.27)
				)
				(hide yes)
			)
		)
		(pin "1"
		)
		(instances
			(project "thunderbolt-gpu-adapter"
				(path ""
					(reference "#FLG0109")
					(unit 1)
				)
			)
		)
	)
	(symbol
		(lib_id "antmicropower:GND")
		(at 199.39 203.2 0)
		(unit 1)
		(exclude_from_sim no)
		(in_bom yes)
		(on_board yes)
		(dnp no)
		(property "Reference" "#PWR0114"
			(at 199.39 209.55 0)
			(effects
				(font
					(size 1.27 1.27)
				)
				(hide yes)
			)
		)
		(property "Value" "GND"
			(at 199.39 207.01 0)
			(effects
				(font
					(size 1.27 1.27)
				)
			)
		)
		(property "Footprint" ""
			(at 199.39 203.2 0)
			(effects
				(font
					(size 1.27 1.27)
				)
				(hide yes)
			)
		)
		(property "Datasheet" ""
			(at 199.39 203.2 0)
			(effects
				(font
					(size 1.27 1.27)
				)
				(hide yes)
			)
		)
		(property "Description" ""
			(at 199.39 203.2 0)
			(effects
				(font
					(size 1.27 1.27)
				)
				(hide yes)
			)
		)
		(property "Author" "Antmicro"
			(at 208.28 210.82 0)
			(effects
				(font
					(size 1.27 1.27)
					(thickness 0.15)
				)
				(justify left bottom)
				(hide yes)
			)
		)
		(property "License" "Apache-2.0"
			(at 208.28 213.36 0)
			(effects
				(font
					(size 1.27 1.27)
					(thickness 0.15)
				)
				(justify left bottom)
				(hide yes)
			)
		)
		(pin "1"
		)
		(instances
			(project "thunderbolt-gpu-adapter"
				(path ""
					(reference "#PWR0114")
					(unit 1)
				)
			)
		)
	)
	(symbol
		(lib_id "antmicroCapacitors0402:C_1u_0402")
		(at 116.84 201.93 90)
		(unit 1)
		(exclude_from_sim no)
		(in_bom yes)
		(on_board yes)
		(dnp no)
		(property "Reference" "C63"
			(at 117.475 197.485 90)
			(effects
				(font
					(size 1.27 1.27)
					(thickness 0.15)
				)
				(justify right)
			)
		)
		(property "Value" "C_1u_0402"
			(at 127 181.61 0)
			(effects
				(font
					(size 1.27 1.27)
					(thickness 0.15)
				)
				(justify left bottom)
				(hide yes)
			)
		)
		(property "Footprint" "antmicro-footprints:C_0402_1005Metric"
			(at 129.54 181.61 0)
			(effects
				(font
					(size 1.27 1.27)
					(thickness 0.15)
				)
				(justify left bottom)
				(hide yes)
			)
		)
		(property "Datasheet" "https://product.tdk.com/en/search/capacitor/ceramic/mlcc/info?part_no=C1005X6S1A105K050BC"
			(at 132.08 181.61 0)
			(effects
				(font
					(size 1.27 1.27)
					(thickness 0.15)
				)
				(justify left bottom)
				(hide yes)
			)
		)
		(property "Description" ""
			(at 116.84 201.93 0)
			(effects
				(font
					(size 1.27 1.27)
				)
				(hide yes)
			)
		)
		(property "MPN" "C1005X6S1A105K050BC"
			(at 134.62 181.61 0)
			(effects
				(font
					(size 1.27 1.27)
					(thickness 0.15)
				)
				(justify left bottom)
				(hide yes)
			)
		)
		(property "Manufacturer" "TDK"
			(at 137.16 181.61 0)
			(effects
				(font
					(size 1.27 1.27)
					(thickness 0.15)
				)
				(justify left bottom)
				(hide yes)
			)
		)
		(property "License" "Apache-2.0"
			(at 139.7 181.61 0)
			(effects
				(font
					(size 1.27 1.27)
					(thickness 0.15)
				)
				(justify left bottom)
				(hide yes)
			)
		)
		(property "Val" "1u"
			(at 117.475 201.295 90)
			(effects
				(font
					(size 1.27 1.27)
					(thickness 0.15)
				)
				(justify right)
			)
		)
		(property "Voltage" ""
			(at 144.78 181.61 0)
			(effects
				(font
					(size 1.27 1.27)
				)
				(justify left bottom)
				(hide yes)
			)
		)
		(property "Dielectric" ""
			(at 147.32 181.61 0)
			(effects
				(font
					(size 1.27 1.27)
				)
				(justify left bottom)
				(hide yes)
			)
		)
		(property "Author" "Antmicro"
			(at 142.24 181.61 0)
			(effects
				(font
					(size 1.27 1.27)
					(thickness 0.15)
				)
				(justify left bottom)
				(hide yes)
			)
		)
		(pin "1"
		)
		(pin "2"
		)
		(instances
			(project "thunderbolt-gpu-adapter"
				(path ""
					(reference "C63")
					(unit 1)
				)
			)
		)
	)
	(symbol
		(lib_id "antmicropower:GND")
		(at 179.07 198.12 0)
		(unit 1)
		(exclude_from_sim no)
		(in_bom yes)
		(on_board yes)
		(dnp no)
		(property "Reference" "#PWR095"
			(at 179.07 204.47 0)
			(effects
				(font
					(size 1.27 1.27)
				)
				(hide yes)
			)
		)
		(property "Value" "GND"
			(at 179.07 201.93 0)
			(effects
				(font
					(size 1.27 1.27)
				)
			)
		)
		(property "Footprint" ""
			(at 179.07 198.12 0)
			(effects
				(font
					(size 1.27 1.27)
				)
				(hide yes)
			)
		)
		(property "Datasheet" ""
			(at 179.07 198.12 0)
			(effects
				(font
					(size 1.27 1.27)
				)
				(hide yes)
			)
		)
		(property "Description" ""
			(at 179.07 198.12 0)
			(effects
				(font
					(size 1.27 1.27)
				)
				(hide yes)
			)
		)
		(property "Author" "Antmicro"
			(at 187.96 205.74 0)
			(effects
				(font
					(size 1.27 1.27)
					(thickness 0.15)
				)
				(justify left bottom)
				(hide yes)
			)
		)
		(property "License" "Apache-2.0"
			(at 187.96 208.28 0)
			(effects
				(font
					(size 1.27 1.27)
					(thickness 0.15)
				)
				(justify left bottom)
				(hide yes)
			)
		)
		(pin "1"
		)
		(instances
			(project "thunderbolt-gpu-adapter"
				(path ""
					(reference "#PWR095")
					(unit 1)
				)
			)
		)
	)
	(symbol
		(lib_id "antmicroCapacitors0402:C_1u_0402")
		(at 186.69 222.25 90)
		(unit 1)
		(exclude_from_sim no)
		(in_bom yes)
		(on_board yes)
		(dnp no)
		(fields_autoplaced yes)
		(property "Reference" "C85"
			(at 187.325 217.805 90)
			(effects
				(font
					(size 1.27 1.27)
					(thickness 0.15)
				)
				(justify right)
			)
		)
		(property "Value" "C_1u_0402"
			(at 196.85 201.93 0)
			(effects
				(font
					(size 1.27 1.27)
					(thickness 0.15)
				)
				(justify left bottom)
				(hide yes)
			)
		)
		(property "Footprint" "antmicro-footprints:C_0402_1005Metric"
			(at 199.39 201.93 0)
			(effects
				(font
					(size 1.27 1.27)
					(thickness 0.15)
				)
				(justify left bottom)
				(hide yes)
			)
		)
		(property "Datasheet" "https://product.tdk.com/en/search/capacitor/ceramic/mlcc/info?part_no=C1005X6S1A105K050BC"
			(at 201.93 201.93 0)
			(effects
				(font
					(size 1.27 1.27)
					(thickness 0.15)
				)
				(justify left bottom)
				(hide yes)
			)
		)
		(property "Description" ""
			(at 186.69 222.25 0)
			(effects
				(font
					(size 1.27 1.27)
				)
				(hide yes)
			)
		)
		(property "MPN" "C1005X6S1A105K050BC"
			(at 204.47 201.93 0)
			(effects
				(font
					(size 1.27 1.27)
					(thickness 0.15)
				)
				(justify left bottom)
				(hide yes)
			)
		)
		(property "Manufacturer" "TDK"
			(at 207.01 201.93 0)
			(effects
				(font
					(size 1.27 1.27)
					(thickness 0.15)
				)
				(justify left bottom)
				(hide yes)
			)
		)
		(property "License" "Apache-2.0"
			(at 209.55 201.93 0)
			(effects
				(font
					(size 1.27 1.27)
					(thickness 0.15)
				)
				(justify left bottom)
				(hide yes)
			)
		)
		(property "Val" "1u"
			(at 187.325 221.615 90)
			(effects
				(font
					(size 1.27 1.27)
					(thickness 0.15)
				)
				(justify right)
			)
		)
		(property "Voltage" ""
			(at 214.63 201.93 0)
			(effects
				(font
					(size 1.27 1.27)
				)
				(justify left bottom)
				(hide yes)
			)
		)
		(property "Dielectric" ""
			(at 217.17 201.93 0)
			(effects
				(font
					(size 1.27 1.27)
				)
				(justify left bottom)
				(hide yes)
			)
		)
		(property "Author" "Antmicro"
			(at 212.09 201.93 0)
			(effects
				(font
					(size 1.27 1.27)
					(thickness 0.15)
				)
				(justify left bottom)
				(hide yes)
			)
		)
		(pin "1"
		)
		(pin "2"
		)
		(instances
			(project "thunderbolt-gpu-adapter"
				(path ""
					(reference "C85")
					(unit 1)
				)
			)
		)
	)
	(symbol
		(lib_id "antmicroCapacitors0402:C_1u_0402")
		(at 193.04 222.25 90)
		(unit 1)
		(exclude_from_sim no)
		(in_bom yes)
		(on_board yes)
		(dnp no)
		(fields_autoplaced yes)
		(property "Reference" "C90"
			(at 193.675 217.805 90)
			(effects
				(font
					(size 1.27 1.27)
					(thickness 0.15)
				)
				(justify right)
			)
		)
		(property "Value" "C_1u_0402"
			(at 203.2 201.93 0)
			(effects
				(font
					(size 1.27 1.27)
					(thickness 0.15)
				)
				(justify left bottom)
				(hide yes)
			)
		)
		(property "Footprint" "antmicro-footprints:C_0402_1005Metric"
			(at 205.74 201.93 0)
			(effects
				(font
					(size 1.27 1.27)
					(thickness 0.15)
				)
				(justify left bottom)
				(hide yes)
			)
		)
		(property "Datasheet" "https://product.tdk.com/en/search/capacitor/ceramic/mlcc/info?part_no=C1005X6S1A105K050BC"
			(at 208.28 201.93 0)
			(effects
				(font
					(size 1.27 1.27)
					(thickness 0.15)
				)
				(justify left bottom)
				(hide yes)
			)
		)
		(property "Description" ""
			(at 193.04 222.25 0)
			(effects
				(font
					(size 1.27 1.27)
				)
				(hide yes)
			)
		)
		(property "MPN" "C1005X6S1A105K050BC"
			(at 210.82 201.93 0)
			(effects
				(font
					(size 1.27 1.27)
					(thickness 0.15)
				)
				(justify left bottom)
				(hide yes)
			)
		)
		(property "Manufacturer" "TDK"
			(at 213.36 201.93 0)
			(effects
				(font
					(size 1.27 1.27)
					(thickness 0.15)
				)
				(justify left bottom)
				(hide yes)
			)
		)
		(property "License" "Apache-2.0"
			(at 215.9 201.93 0)
			(effects
				(font
					(size 1.27 1.27)
					(thickness 0.15)
				)
				(justify left bottom)
				(hide yes)
			)
		)
		(property "Val" "1u"
			(at 193.675 221.615 90)
			(effects
				(font
					(size 1.27 1.27)
					(thickness 0.15)
				)
				(justify right)
			)
		)
		(property "Voltage" ""
			(at 220.98 201.93 0)
			(effects
				(font
					(size 1.27 1.27)
				)
				(justify left bottom)
				(hide yes)
			)
		)
		(property "Dielectric" ""
			(at 223.52 201.93 0)
			(effects
				(font
					(size 1.27 1.27)
				)
				(justify left bottom)
				(hide yes)
			)
		)
		(property "Author" "Antmicro"
			(at 218.44 201.93 0)
			(effects
				(font
					(size 1.27 1.27)
					(thickness 0.15)
				)
				(justify left bottom)
				(hide yes)
			)
		)
		(pin "1"
		)
		(pin "2"
		)
		(instances
			(project "thunderbolt-gpu-adapter"
				(path ""
					(reference "C90")
					(unit 1)
				)
			)
		)
	)
	(symbol
		(lib_id "antmicroFixedInductors:L_680n_7.6A_IHLP1616BZ")
		(at 179.07 193.04 0)
		(unit 1)
		(exclude_from_sim no)
		(in_bom yes)
		(on_board yes)
		(dnp no)
		(property "Reference" "L3"
			(at 177.8 191.77 0)
			(effects
				(font
					(size 1.27 1.27)
					(thickness 0.15)
				)
			)
		)
		(property "Value" "L_680n_7.6A_IHLP1616BZ"
			(at 193.04 195.58 0)
			(effects
				(font
					(size 1.27 1.27)
					(thickness 0.15)
				)
				(justify left bottom)
				(hide yes)
			)
		)
		(property "Footprint" "antmicro-footprints:L_Vishay-IHLP1616BZ"
			(at 193.04 200.66 0)
			(effects
				(font
					(size 1.27 1.27)
					(thickness 0.15)
				)
				(justify left bottom)
				(hide yes)
			)
		)
		(property "Datasheet" "https://www.mouser.com/datasheet/2/427/ihlp1616bz5a-1763007.pdf"
			(at 193.04 203.2 0)
			(effects
				(font
					(size 1.27 1.27)
					(thickness 0.15)
				)
				(justify left bottom)
				(hide yes)
			)
		)
		(property "Description" ""
			(at 179.07 193.04 0)
			(effects
				(font
					(size 1.27 1.27)
				)
				(hide yes)
			)
		)
		(property "Val" "680n/7.6A"
			(at 189.23 191.77 0)
			(effects
				(font
					(size 1.27 1.27)
					(thickness 0.15)
				)
			)
		)
		(property "Manufacturer" "Vishay"
			(at 193.04 205.74 0)
			(effects
				(font
					(size 1.27 1.27)
					(thickness 0.15)
				)
				(justify left bottom)
				(hide yes)
			)
		)
		(property "MPN" "IHLP1616BZERR68M5A"
			(at 193.04 208.28 0)
			(effects
				(font
					(size 1.27 1.27)
					(thickness 0.15)
				)
				(justify left bottom)
				(hide yes)
			)
		)
		(property "ISat" "6.8 A"
			(at 193.04 209.55 0)
			(effects
				(font
					(size 1.27 1.27)
				)
				(justify left)
				(hide yes)
			)
		)
		(property "IMax" "7.6 A"
			(at 193.04 213.36 0)
			(effects
				(font
					(size 1.27 1.27)
					(thickness 0.15)
				)
				(justify left bottom)
				(hide yes)
			)
		)
		(property "Size" "4.06x4.06"
			(at 193.04 215.9 0)
			(effects
				(font
					(size 1.27 1.27)
					(thickness 0.15)
				)
				(justify left bottom)
				(hide yes)
			)
		)
		(property "Author" "Antmicro"
			(at 193.04 218.44 0)
			(effects
				(font
					(size 1.27 1.27)
					(thickness 0.15)
				)
				(justify left bottom)
				(hide yes)
			)
		)
		(property "License" "Apache-2.0"
			(at 193.04 220.98 0)
			(effects
				(font
					(size 1.27 1.27)
					(thickness 0.15)
				)
				(justify left bottom)
				(hide yes)
			)
		)
		(pin "1"
		)
		(pin "2"
		)
		(instances
			(project "thunderbolt-gpu-adapter"
				(path ""
					(reference "L3")
					(unit 1)
				)
			)
		)
	)
	(symbol
		(lib_id "antmicropower:GND")
		(at 231.14 134.62 0)
		(unit 1)
		(exclude_from_sim no)
		(in_bom yes)
		(on_board yes)
		(dnp no)
		(property "Reference" "#PWR0108"
			(at 231.14 140.97 0)
			(effects
				(font
					(size 1.27 1.27)
				)
				(hide yes)
			)
		)
		(property "Value" "GND"
			(at 231.14 138.43 0)
			(effects
				(font
					(size 1.27 1.27)
				)
			)
		)
		(property "Footprint" ""
			(at 231.14 134.62 0)
			(effects
				(font
					(size 1.27 1.27)
				)
				(hide yes)
			)
		)
		(property "Datasheet" ""
			(at 231.14 134.62 0)
			(effects
				(font
					(size 1.27 1.27)
				)
				(hide yes)
			)
		)
		(property "Description" ""
			(at 231.14 134.62 0)
			(effects
				(font
					(size 1.27 1.27)
				)
				(hide yes)
			)
		)
		(property "Author" "Antmicro"
			(at 240.03 142.24 0)
			(effects
				(font
					(size 1.27 1.27)
					(thickness 0.15)
				)
				(justify left bottom)
				(hide yes)
			)
		)
		(property "License" "Apache-2.0"
			(at 240.03 144.78 0)
			(effects
				(font
					(size 1.27 1.27)
					(thickness 0.15)
				)
				(justify left bottom)
				(hide yes)
			)
		)
		(pin "1"
		)
		(instances
			(project "thunderbolt-gpu-adapter"
				(path ""
					(reference "#PWR0108")
					(unit 1)
				)
			)
		)
	)
	(symbol
		(lib_id "antmicroCapacitors0402:C_100n_0402")
		(at 212.09 165.1 90)
		(unit 1)
		(exclude_from_sim no)
		(in_bom yes)
		(on_board yes)
		(dnp no)
		(fields_autoplaced yes)
		(property "Reference" "C97"
			(at 214.63 161.2836 90)
			(effects
				(font
					(size 1.27 1.27)
					(thickness 0.15)
				)
				(justify right)
			)
		)
		(property "Value" "C_100n_0402"
			(at 222.25 144.78 0)
			(effects
				(font
					(size 1.27 1.27)
					(thickness 0.15)
				)
				(justify left bottom)
				(hide yes)
			)
		)
		(property "Footprint" "antmicro-footprints:C_0402_1005Metric"
			(at 224.79 144.78 0)
			(effects
				(font
					(size 1.27 1.27)
					(thickness 0.15)
				)
				(justify left bottom)
				(hide yes)
			)
		)
		(property "Datasheet" "https://www.murata.com/products/productdetail?partno=GRM155R61H104KE14%23"
			(at 227.33 144.78 0)
			(effects
				(font
					(size 1.27 1.27)
					(thickness 0.15)
				)
				(justify left bottom)
				(hide yes)
			)
		)
		(property "Description" ""
			(at 212.09 165.1 0)
			(effects
				(font
					(size 1.27 1.27)
				)
				(hide yes)
			)
		)
		(property "MPN" "GRM155R61H104KE14D"
			(at 229.87 144.78 0)
			(effects
				(font
					(size 1.27 1.27)
					(thickness 0.15)
				)
				(justify left bottom)
				(hide yes)
			)
		)
		(property "Manufacturer" "Murata"
			(at 232.41 144.78 0)
			(effects
				(font
					(size 1.27 1.27)
					(thickness 0.15)
				)
				(justify left bottom)
				(hide yes)
			)
		)
		(property "License" "Apache-2.0"
			(at 234.95 144.78 0)
			(effects
				(font
					(size 1.27 1.27)
					(thickness 0.15)
				)
				(justify left bottom)
				(hide yes)
			)
		)
		(property "Val" "100n"
			(at 214.63 163.8236 90)
			(effects
				(font
					(size 1.27 1.27)
					(thickness 0.15)
				)
				(justify right)
			)
		)
		(property "Voltage" "50V"
			(at 240.03 144.78 0)
			(effects
				(font
					(size 1.27 1.27)
				)
				(justify left bottom)
				(hide yes)
			)
		)
		(property "Dielectric" "X5R"
			(at 242.57 144.78 0)
			(effects
				(font
					(size 1.27 1.27)
				)
				(justify left bottom)
				(hide yes)
			)
		)
		(property "Author" "Antmicro"
			(at 237.49 144.78 0)
			(effects
				(font
					(size 1.27 1.27)
					(thickness 0.15)
				)
				(justify left bottom)
				(hide yes)
			)
		)
		(pin "1"
		)
		(pin "2"
		)
		(instances
			(project "thunderbolt-gpu-adapter"
				(path ""
					(reference "C97")
					(unit 1)
				)
			)
		)
	)
	(symbol
		(lib_id "antmicroCapacitors0402:C_100n_0402")
		(at 180.34 133.35 90)
		(unit 1)
		(exclude_from_sim no)
		(in_bom yes)
		(on_board yes)
		(dnp no)
		(property "Reference" "C88"
			(at 180.975 128.905 90)
			(effects
				(font
					(size 1.27 1.27)
					(thickness 0.15)
				)
				(justify right)
			)
		)
		(property "Value" "C_100n_0402"
			(at 190.5 113.03 0)
			(effects
				(font
					(size 1.27 1.27)
					(thickness 0.15)
				)
				(justify left bottom)
				(hide yes)
			)
		)
		(property "Footprint" "antmicro-footprints:C_0402_1005Metric"
			(at 193.04 113.03 0)
			(effects
				(font
					(size 1.27 1.27)
					(thickness 0.15)
				)
				(justify left bottom)
				(hide yes)
			)
		)
		(property "Datasheet" "https://www.murata.com/products/productdetail?partno=GRM155R61H104KE14%23"
			(at 195.58 113.03 0)
			(effects
				(font
					(size 1.27 1.27)
					(thickness 0.15)
				)
				(justify left bottom)
				(hide yes)
			)
		)
		(property "Description" ""
			(at 180.34 133.35 0)
			(effects
				(font
					(size 1.27 1.27)
				)
				(hide yes)
			)
		)
		(property "MPN" "GRM155R61H104KE14D"
			(at 198.12 113.03 0)
			(effects
				(font
					(size 1.27 1.27)
					(thickness 0.15)
				)
				(justify left bottom)
				(hide yes)
			)
		)
		(property "Manufacturer" "Murata"
			(at 200.66 113.03 0)
			(effects
				(font
					(size 1.27 1.27)
					(thickness 0.15)
				)
				(justify left bottom)
				(hide yes)
			)
		)
		(property "License" "Apache-2.0"
			(at 203.2 113.03 0)
			(effects
				(font
					(size 1.27 1.27)
					(thickness 0.15)
				)
				(justify left bottom)
				(hide yes)
			)
		)
		(property "Val" "100n"
			(at 180.975 132.715 90)
			(effects
				(font
					(size 1.27 1.27)
					(thickness 0.15)
				)
				(justify right)
			)
		)
		(property "Voltage" "50V"
			(at 208.28 113.03 0)
			(effects
				(font
					(size 1.27 1.27)
				)
				(justify left bottom)
				(hide yes)
			)
		)
		(property "Dielectric" "X5R"
			(at 210.82 113.03 0)
			(effects
				(font
					(size 1.27 1.27)
				)
				(justify left bottom)
				(hide yes)
			)
		)
		(property "Author" "Antmicro"
			(at 205.74 113.03 0)
			(effects
				(font
					(size 1.27 1.27)
					(thickness 0.15)
				)
				(justify left bottom)
				(hide yes)
			)
		)
		(pin "1"
		)
		(pin "2"
		)
		(instances
			(project "thunderbolt-gpu-adapter"
				(path ""
					(reference "C88")
					(unit 1)
				)
			)
		)
	)
	(symbol
		(lib_id "antmicroCapacitors0402:C_1u_0402")
		(at 111.76 166.37 90)
		(unit 1)
		(exclude_from_sim no)
		(in_bom yes)
		(on_board yes)
		(dnp no)
		(property "Reference" "C65"
			(at 112.395 161.925 90)
			(effects
				(font
					(size 1.27 1.27)
					(thickness 0.15)
				)
				(justify right)
			)
		)
		(property "Value" "C_1u_0402"
			(at 121.92 146.05 0)
			(effects
				(font
					(size 1.27 1.27)
					(thickness 0.15)
				)
				(justify left bottom)
				(hide yes)
			)
		)
		(property "Footprint" "antmicro-footprints:C_0402_1005Metric"
			(at 124.46 146.05 0)
			(effects
				(font
					(size 1.27 1.27)
					(thickness 0.15)
				)
				(justify left bottom)
				(hide yes)
			)
		)
		(property "Datasheet" "https://product.tdk.com/en/search/capacitor/ceramic/mlcc/info?part_no=C1005X6S1A105K050BC"
			(at 127 146.05 0)
			(effects
				(font
					(size 1.27 1.27)
					(thickness 0.15)
				)
				(justify left bottom)
				(hide yes)
			)
		)
		(property "Description" ""
			(at 111.76 166.37 0)
			(effects
				(font
					(size 1.27 1.27)
				)
				(hide yes)
			)
		)
		(property "MPN" "C1005X6S1A105K050BC"
			(at 129.54 146.05 0)
			(effects
				(font
					(size 1.27 1.27)
					(thickness 0.15)
				)
				(justify left bottom)
				(hide yes)
			)
		)
		(property "Manufacturer" "TDK"
			(at 132.08 146.05 0)
			(effects
				(font
					(size 1.27 1.27)
					(thickness 0.15)
				)
				(justify left bottom)
				(hide yes)
			)
		)
		(property "License" "Apache-2.0"
			(at 134.62 146.05 0)
			(effects
				(font
					(size 1.27 1.27)
					(thickness 0.15)
				)
				(justify left bottom)
				(hide yes)
			)
		)
		(property "Val" "1u"
			(at 112.395 165.735 90)
			(effects
				(font
					(size 1.27 1.27)
					(thickness 0.15)
				)
				(justify right)
			)
		)
		(property "Voltage" ""
			(at 139.7 146.05 0)
			(effects
				(font
					(size 1.27 1.27)
				)
				(justify left bottom)
				(hide yes)
			)
		)
		(property "Dielectric" ""
			(at 142.24 146.05 0)
			(effects
				(font
					(size 1.27 1.27)
				)
				(justify left bottom)
				(hide yes)
			)
		)
		(property "Author" "Antmicro"
			(at 137.16 146.05 0)
			(effects
				(font
					(size 1.27 1.27)
					(thickness 0.15)
				)
				(justify left bottom)
				(hide yes)
			)
		)
		(pin "1"
		)
		(pin "2"
		)
		(instances
			(project "thunderbolt-gpu-adapter"
				(path ""
					(reference "C65")
					(unit 1)
				)
			)
		)
	)
	(symbol
		(lib_id "antmicropower:GND")
		(at 111.76 224.79 0)
		(unit 1)
		(exclude_from_sim no)
		(in_bom yes)
		(on_board yes)
		(dnp no)
		(property "Reference" "#PWR091"
			(at 111.76 231.14 0)
			(effects
				(font
					(size 1.27 1.27)
				)
				(hide yes)
			)
		)
		(property "Value" "GND"
			(at 111.76 228.6 0)
			(effects
				(font
					(size 1.27 1.27)
				)
			)
		)
		(property "Footprint" ""
			(at 111.76 224.79 0)
			(effects
				(font
					(size 1.27 1.27)
				)
				(hide yes)
			)
		)
		(property "Datasheet" ""
			(at 111.76 224.79 0)
			(effects
				(font
					(size 1.27 1.27)
				)
				(hide yes)
			)
		)
		(property "Description" ""
			(at 111.76 224.79 0)
			(effects
				(font
					(size 1.27 1.27)
				)
				(hide yes)
			)
		)
		(property "Author" "Antmicro"
			(at 120.65 232.41 0)
			(effects
				(font
					(size 1.27 1.27)
					(thickness 0.15)
				)
				(justify left bottom)
				(hide yes)
			)
		)
		(property "License" "Apache-2.0"
			(at 120.65 234.95 0)
			(effects
				(font
					(size 1.27 1.27)
					(thickness 0.15)
				)
				(justify left bottom)
				(hide yes)
			)
		)
		(pin "1"
		)
		(instances
			(project "thunderbolt-gpu-adapter"
				(path ""
					(reference "#PWR091")
					(unit 1)
				)
			)
		)
	)
	(symbol
		(lib_id "antmicroCapacitors0402:C_1u_0402")
		(at 180.34 182.88 90)
		(unit 1)
		(exclude_from_sim no)
		(in_bom yes)
		(on_board yes)
		(dnp no)
		(property "Reference" "C74"
			(at 180.975 178.435 90)
			(effects
				(font
					(size 1.27 1.27)
					(thickness 0.15)
				)
				(justify right)
			)
		)
		(property "Value" "C_1u_0402"
			(at 190.5 162.56 0)
			(effects
				(font
					(size 1.27 1.27)
					(thickness 0.15)
				)
				(justify left bottom)
				(hide yes)
			)
		)
		(property "Footprint" "antmicro-footprints:C_0402_1005Metric"
			(at 193.04 162.56 0)
			(effects
				(font
					(size 1.27 1.27)
					(thickness 0.15)
				)
				(justify left bottom)
				(hide yes)
			)
		)
		(property "Datasheet" "https://product.tdk.com/en/search/capacitor/ceramic/mlcc/info?part_no=C1005X6S1A105K050BC"
			(at 195.58 162.56 0)
			(effects
				(font
					(size 1.27 1.27)
					(thickness 0.15)
				)
				(justify left bottom)
				(hide yes)
			)
		)
		(property "Description" ""
			(at 180.34 182.88 0)
			(effects
				(font
					(size 1.27 1.27)
				)
				(hide yes)
			)
		)
		(property "MPN" "C1005X6S1A105K050BC"
			(at 198.12 162.56 0)
			(effects
				(font
					(size 1.27 1.27)
					(thickness 0.15)
				)
				(justify left bottom)
				(hide yes)
			)
		)
		(property "Manufacturer" "TDK"
			(at 200.66 162.56 0)
			(effects
				(font
					(size 1.27 1.27)
					(thickness 0.15)
				)
				(justify left bottom)
				(hide yes)
			)
		)
		(property "License" "Apache-2.0"
			(at 203.2 162.56 0)
			(effects
				(font
					(size 1.27 1.27)
					(thickness 0.15)
				)
				(justify left bottom)
				(hide yes)
			)
		)
		(property "Val" "1u"
			(at 180.975 182.245 90)
			(effects
				(font
					(size 1.27 1.27)
					(thickness 0.15)
				)
				(justify right)
			)
		)
		(property "Voltage" ""
			(at 208.28 162.56 0)
			(effects
				(font
					(size 1.27 1.27)
				)
				(justify left bottom)
				(hide yes)
			)
		)
		(property "Dielectric" ""
			(at 210.82 162.56 0)
			(effects
				(font
					(size 1.27 1.27)
				)
				(justify left bottom)
				(hide yes)
			)
		)
		(property "Author" "Antmicro"
			(at 205.74 162.56 0)
			(effects
				(font
					(size 1.27 1.27)
					(thickness 0.15)
				)
				(justify left bottom)
				(hide yes)
			)
		)
		(pin "1"
		)
		(pin "2"
		)
		(instances
			(project "thunderbolt-gpu-adapter"
				(path ""
					(reference "C74")
					(unit 1)
				)
			)
		)
	)
	(symbol
		(lib_id "antmicropower:GND")
		(at 105.41 151.13 0)
		(unit 1)
		(exclude_from_sim no)
		(in_bom yes)
		(on_board yes)
		(dnp no)
		(property "Reference" "#PWR086"
			(at 105.41 157.48 0)
			(effects
				(font
					(size 1.27 1.27)
				)
				(hide yes)
			)
		)
		(property "Value" "GND"
			(at 105.41 154.94 0)
			(effects
				(font
					(size 1.27 1.27)
				)
			)
		)
		(property "Footprint" ""
			(at 105.41 151.13 0)
			(effects
				(font
					(size 1.27 1.27)
				)
				(hide yes)
			)
		)
		(property "Datasheet" ""
			(at 105.41 151.13 0)
			(effects
				(font
					(size 1.27 1.27)
				)
				(hide yes)
			)
		)
		(property "Description" ""
			(at 105.41 151.13 0)
			(effects
				(font
					(size 1.27 1.27)
				)
				(hide yes)
			)
		)
		(property "Author" "Antmicro"
			(at 114.3 158.75 0)
			(effects
				(font
					(size 1.27 1.27)
					(thickness 0.15)
				)
				(justify left bottom)
				(hide yes)
			)
		)
		(property "License" "Apache-2.0"
			(at 114.3 161.29 0)
			(effects
				(font
					(size 1.27 1.27)
					(thickness 0.15)
				)
				(justify left bottom)
				(hide yes)
			)
		)
		(pin "1"
		)
		(instances
			(project "thunderbolt-gpu-adapter"
				(path ""
					(reference "#PWR086")
					(unit 1)
				)
			)
		)
	)
	(symbol
		(lib_id "antmicroOperationalAmplifiers:MCP6541_SOT23-5")
		(at 233.68 213.36 0)
		(unit 1)
		(exclude_from_sim no)
		(in_bom yes)
		(on_board yes)
		(dnp no)
		(property "Reference" "U13"
			(at 237.49 218.44 0)
			(effects
				(font
					(size 1.27 1.27)
					(thickness 0.15)
				)
			)
		)
		(property "Value" "MCP6541_SOT23-5"
			(at 259.08 220.98 0)
			(effects
				(font
					(size 1.27 1.27)
					(thickness 0.15)
				)
				(justify left bottom)
				(hide yes)
			)
		)
		(property "Footprint" "antmicro-footprints:SOT-23-5"
			(at 259.08 223.52 0)
			(effects
				(font
					(size 1.27 1.27)
					(thickness 0.15)
				)
				(justify left bottom)
				(hide yes)
			)
		)
		(property "Datasheet" "https://www.farnell.com/datasheets/1641674.pdf"
			(at 259.08 226.06 0)
			(effects
				(font
					(size 1.27 1.27)
					(thickness 0.15)
				)
				(justify left bottom)
				(hide yes)
			)
		)
		(property "Description" ""
			(at 233.68 213.36 0)
			(effects
				(font
					(size 1.27 1.27)
				)
				(hide yes)
			)
		)
		(property "MPN" "MCP6541T-E/OT"
			(at 237.49 220.98 0)
			(effects
				(font
					(size 1.27 1.27)
					(thickness 0.15)
				)
			)
		)
		(property "Manufacturer" "Microchip Technology"
			(at 259.08 231.14 0)
			(effects
				(font
					(size 1.27 1.27)
					(thickness 0.15)
				)
				(justify left bottom)
				(hide yes)
			)
		)
		(property "Author" "Antmicro"
			(at 259.08 233.68 0)
			(effects
				(font
					(size 1.27 1.27)
					(thickness 0.15)
				)
				(justify left bottom)
				(hide yes)
			)
		)
		(property "License" "Apache-2.0"
			(at 259.08 236.22 0)
			(effects
				(font
					(size 1.27 1.27)
					(thickness 0.15)
				)
				(justify left bottom)
				(hide yes)
			)
		)
		(pin "1"
		)
		(pin "3"
		)
		(pin "4"
		)
		(pin "2"
		)
		(pin "5"
		)
		(instances
			(project "thunderbolt-gpu-adapter"
				(path ""
					(reference "U13")
					(unit 1)
				)
			)
		)
	)
	(symbol
		(lib_id "antmicropower:GND")
		(at 205.74 184.15 0)
		(unit 1)
		(exclude_from_sim no)
		(in_bom yes)
		(on_board yes)
		(dnp no)
		(property "Reference" "#PWR0115"
			(at 205.74 190.5 0)
			(effects
				(font
					(size 1.27 1.27)
				)
				(hide yes)
			)
		)
		(property "Value" "GND"
			(at 205.74 187.96 0)
			(effects
				(font
					(size 1.27 1.27)
				)
			)
		)
		(property "Footprint" ""
			(at 205.74 184.15 0)
			(effects
				(font
					(size 1.27 1.27)
				)
				(hide yes)
			)
		)
		(property "Datasheet" ""
			(at 205.74 184.15 0)
			(effects
				(font
					(size 1.27 1.27)
				)
				(hide yes)
			)
		)
		(property "Description" ""
			(at 205.74 184.15 0)
			(effects
				(font
					(size 1.27 1.27)
				)
				(hide yes)
			)
		)
		(property "Author" "Antmicro"
			(at 214.63 191.77 0)
			(effects
				(font
					(size 1.27 1.27)
					(thickness 0.15)
				)
				(justify left bottom)
				(hide yes)
			)
		)
		(property "License" "Apache-2.0"
			(at 214.63 194.31 0)
			(effects
				(font
					(size 1.27 1.27)
					(thickness 0.15)
				)
				(justify left bottom)
				(hide yes)
			)
		)
		(pin "1"
		)
		(instances
			(project "thunderbolt-gpu-adapter"
				(path ""
					(reference "#PWR0115")
					(unit 1)
				)
			)
		)
	)
	(symbol
		(lib_id "antmicropower:GND")
		(at 186.69 224.79 0)
		(unit 1)
		(exclude_from_sim no)
		(in_bom yes)
		(on_board yes)
		(dnp no)
		(fields_autoplaced yes)
		(property "Reference" "#PWR0113"
			(at 186.69 231.14 0)
			(effects
				(font
					(size 1.27 1.27)
				)
				(hide yes)
			)
		)
		(property "Value" "GND"
			(at 186.69 228.6 0)
			(effects
				(font
					(size 1.27 1.27)
				)
			)
		)
		(property "Footprint" ""
			(at 186.69 224.79 0)
			(effects
				(font
					(size 1.27 1.27)
				)
				(hide yes)
			)
		)
		(property "Datasheet" ""
			(at 186.69 224.79 0)
			(effects
				(font
					(size 1.27 1.27)
				)
				(hide yes)
			)
		)
		(property "Description" ""
			(at 186.69 224.79 0)
			(effects
				(font
					(size 1.27 1.27)
				)
				(hide yes)
			)
		)
		(property "Author" "Antmicro"
			(at 195.58 232.41 0)
			(effects
				(font
					(size 1.27 1.27)
					(thickness 0.15)
				)
				(justify left bottom)
				(hide yes)
			)
		)
		(property "License" "Apache-2.0"
			(at 195.58 234.95 0)
			(effects
				(font
					(size 1.27 1.27)
					(thickness 0.15)
				)
				(justify left bottom)
				(hide yes)
			)
		)
		(pin "1"
		)
		(instances
			(project "thunderbolt-gpu-adapter"
				(path ""
					(reference "#PWR0113")
					(unit 1)
				)
			)
		)
	)
	(symbol
		(lib_id "antmicropower:GND")
		(at 199.39 224.79 0)
		(unit 1)
		(exclude_from_sim no)
		(in_bom yes)
		(on_board yes)
		(dnp no)
		(property "Reference" "#PWR0100"
			(at 199.39 231.14 0)
			(effects
				(font
					(size 1.27 1.27)
				)
				(hide yes)
			)
		)
		(property "Value" "GND"
			(at 199.39 228.6 0)
			(effects
				(font
					(size 1.27 1.27)
				)
			)
		)
		(property "Footprint" ""
			(at 199.39 224.79 0)
			(effects
				(font
					(size 1.27 1.27)
				)
				(hide yes)
			)
		)
		(property "Datasheet" ""
			(at 199.39 224.79 0)
			(effects
				(font
					(size 1.27 1.27)
				)
				(hide yes)
			)
		)
		(property "Description" ""
			(at 199.39 224.79 0)
			(effects
				(font
					(size 1.27 1.27)
				)
				(hide yes)
			)
		)
		(property "Author" "Antmicro"
			(at 208.28 232.41 0)
			(effects
				(font
					(size 1.27 1.27)
					(thickness 0.15)
				)
				(justify left bottom)
				(hide yes)
			)
		)
		(property "License" "Apache-2.0"
			(at 208.28 234.95 0)
			(effects
				(font
					(size 1.27 1.27)
					(thickness 0.15)
				)
				(justify left bottom)
				(hide yes)
			)
		)
		(pin "1"
		)
		(instances
			(project "thunderbolt-gpu-adapter"
				(path ""
					(reference "#PWR0100")
					(unit 1)
				)
			)
		)
	)
	(symbol
		(lib_id "antmicropower:GND")
		(at 116.84 287.02 0)
		(unit 1)
		(exclude_from_sim no)
		(in_bom yes)
		(on_board yes)
		(dnp no)
		(property "Reference" "#PWR0204"
			(at 116.84 293.37 0)
			(effects
				(font
					(size 1.27 1.27)
				)
				(hide yes)
			)
		)
		(property "Value" "GND"
			(at 116.84 290.83 0)
			(effects
				(font
					(size 1.27 1.27)
				)
			)
		)
		(property "Footprint" ""
			(at 116.84 287.02 0)
			(effects
				(font
					(size 1.27 1.27)
				)
				(hide yes)
			)
		)
		(property "Datasheet" ""
			(at 116.84 287.02 0)
			(effects
				(font
					(size 1.27 1.27)
				)
				(hide yes)
			)
		)
		(property "Description" ""
			(at 116.84 287.02 0)
			(effects
				(font
					(size 1.27 1.27)
				)
				(hide yes)
			)
		)
		(property "Author" "Antmicro"
			(at 125.73 294.64 0)
			(effects
				(font
					(size 1.27 1.27)
					(thickness 0.15)
				)
				(justify left bottom)
				(hide yes)
			)
		)
		(property "License" "Apache-2.0"
			(at 125.73 297.18 0)
			(effects
				(font
					(size 1.27 1.27)
					(thickness 0.15)
				)
				(justify left bottom)
				(hide yes)
			)
		)
		(pin "1"
		)
		(instances
			(project "thunderbolt-gpu-adapter"
				(path ""
					(reference "#PWR0204")
					(unit 1)
				)
			)
		)
	)
	(symbol
		(lib_id "antmicropower:GND")
		(at 218.44 134.62 0)
		(unit 1)
		(exclude_from_sim no)
		(in_bom yes)
		(on_board yes)
		(dnp no)
		(property "Reference" "#PWR098"
			(at 218.44 140.97 0)
			(effects
				(font
					(size 1.27 1.27)
				)
				(hide yes)
			)
		)
		(property "Value" "GND"
			(at 218.44 138.43 0)
			(effects
				(font
					(size 1.27 1.27)
				)
			)
		)
		(property "Footprint" ""
			(at 218.44 134.62 0)
			(effects
				(font
					(size 1.27 1.27)
				)
				(hide yes)
			)
		)
		(property "Datasheet" ""
			(at 218.44 134.62 0)
			(effects
				(font
					(size 1.27 1.27)
				)
				(hide yes)
			)
		)
		(property "Description" ""
			(at 218.44 134.62 0)
			(effects
				(font
					(size 1.27 1.27)
				)
				(hide yes)
			)
		)
		(property "Author" "Antmicro"
			(at 227.33 142.24 0)
			(effects
				(font
					(size 1.27 1.27)
					(thickness 0.15)
				)
				(justify left bottom)
				(hide yes)
			)
		)
		(property "License" "Apache-2.0"
			(at 227.33 144.78 0)
			(effects
				(font
					(size 1.27 1.27)
					(thickness 0.15)
				)
				(justify left bottom)
				(hide yes)
			)
		)
		(pin "1"
		)
		(instances
			(project "thunderbolt-gpu-adapter"
				(path ""
					(reference "#PWR098")
					(unit 1)
				)
			)
		)
	)
	(symbol
		(lib_id "antmicroCapacitors0402:C_100n_0402")
		(at 212.09 133.35 90)
		(unit 1)
		(exclude_from_sim no)
		(in_bom yes)
		(on_board yes)
		(dnp no)
		(property "Reference" "C152"
			(at 212.725 128.905 90)
			(effects
				(font
					(size 1.27 1.27)
					(thickness 0.15)
				)
				(justify right)
			)
		)
		(property "Value" "C_100n_0402"
			(at 222.25 113.03 0)
			(effects
				(font
					(size 1.27 1.27)
					(thickness 0.15)
				)
				(justify left bottom)
				(hide yes)
			)
		)
		(property "Footprint" "antmicro-footprints:C_0402_1005Metric"
			(at 224.79 113.03 0)
			(effects
				(font
					(size 1.27 1.27)
					(thickness 0.15)
				)
				(justify left bottom)
				(hide yes)
			)
		)
		(property "Datasheet" "https://www.murata.com/products/productdetail?partno=GRM155R61H104KE14%23"
			(at 227.33 113.03 0)
			(effects
				(font
					(size 1.27 1.27)
					(thickness 0.15)
				)
				(justify left bottom)
				(hide yes)
			)
		)
		(property "Description" ""
			(at 212.09 133.35 0)
			(effects
				(font
					(size 1.27 1.27)
				)
				(hide yes)
			)
		)
		(property "MPN" "GRM155R61H104KE14D"
			(at 229.87 113.03 0)
			(effects
				(font
					(size 1.27 1.27)
					(thickness 0.15)
				)
				(justify left bottom)
				(hide yes)
			)
		)
		(property "Manufacturer" "Murata"
			(at 232.41 113.03 0)
			(effects
				(font
					(size 1.27 1.27)
					(thickness 0.15)
				)
				(justify left bottom)
				(hide yes)
			)
		)
		(property "License" "Apache-2.0"
			(at 234.95 113.03 0)
			(effects
				(font
					(size 1.27 1.27)
					(thickness 0.15)
				)
				(justify left bottom)
				(hide yes)
			)
		)
		(property "Val" "100n"
			(at 212.725 132.715 90)
			(effects
				(font
					(size 1.27 1.27)
					(thickness 0.15)
				)
				(justify right)
			)
		)
		(property "Voltage" "50V"
			(at 240.03 113.03 0)
			(effects
				(font
					(size 1.27 1.27)
				)
				(justify left bottom)
				(hide yes)
			)
		)
		(property "Dielectric" "X5R"
			(at 242.57 113.03 0)
			(effects
				(font
					(size 1.27 1.27)
				)
				(justify left bottom)
				(hide yes)
			)
		)
		(property "Author" "Antmicro"
			(at 237.49 113.03 0)
			(effects
				(font
					(size 1.27 1.27)
					(thickness 0.15)
				)
				(justify left bottom)
				(hide yes)
			)
		)
		(pin "1"
		)
		(pin "2"
		)
		(instances
			(project "thunderbolt-gpu-adapter"
				(path ""
					(reference "C152")
					(unit 1)
				)
			)
		)
	)
	(symbol
		(lib_id "antmicropower:GND")
		(at 186.69 152.4 0)
		(unit 1)
		(exclude_from_sim no)
		(in_bom yes)
		(on_board yes)
		(dnp no)
		(property "Reference" "#PWR0102"
			(at 186.69 158.75 0)
			(effects
				(font
					(size 1.27 1.27)
				)
				(hide yes)
			)
		)
		(property "Value" "GND"
			(at 186.69 156.21 0)
			(effects
				(font
					(size 1.27 1.27)
				)
			)
		)
		(property "Footprint" ""
			(at 186.69 152.4 0)
			(effects
				(font
					(size 1.27 1.27)
				)
				(hide yes)
			)
		)
		(property "Datasheet" ""
			(at 186.69 152.4 0)
			(effects
				(font
					(size 1.27 1.27)
				)
				(hide yes)
			)
		)
		(property "Description" ""
			(at 186.69 152.4 0)
			(effects
				(font
					(size 1.27 1.27)
				)
				(hide yes)
			)
		)
		(property "Author" "Antmicro"
			(at 195.58 160.02 0)
			(effects
				(font
					(size 1.27 1.27)
					(thickness 0.15)
				)
				(justify left bottom)
				(hide yes)
			)
		)
		(property "License" "Apache-2.0"
			(at 195.58 162.56 0)
			(effects
				(font
					(size 1.27 1.27)
					(thickness 0.15)
				)
				(justify left bottom)
				(hide yes)
			)
		)
		(pin "1"
		)
		(instances
			(project "thunderbolt-gpu-adapter"
				(path ""
					(reference "#PWR0102")
					(unit 1)
				)
			)
		)
	)
	(symbol
		(lib_id "antmicroCapacitors0402:C_1u_0402")
		(at 116.84 148.59 90)
		(unit 1)
		(exclude_from_sim no)
		(in_bom yes)
		(on_board yes)
		(dnp no)
		(property "Reference" "C67"
			(at 117.475 144.145 90)
			(effects
				(font
					(size 1.27 1.27)
					(thickness 0.15)
				)
				(justify right)
			)
		)
		(property "Value" "C_1u_0402"
			(at 127 128.27 0)
			(effects
				(font
					(size 1.27 1.27)
					(thickness 0.15)
				)
				(justify left bottom)
				(hide yes)
			)
		)
		(property "Footprint" "antmicro-footprints:C_0402_1005Metric"
			(at 129.54 128.27 0)
			(effects
				(font
					(size 1.27 1.27)
					(thickness 0.15)
				)
				(justify left bottom)
				(hide yes)
			)
		)
		(property "Datasheet" "https://product.tdk.com/en/search/capacitor/ceramic/mlcc/info?part_no=C1005X6S1A105K050BC"
			(at 132.08 128.27 0)
			(effects
				(font
					(size 1.27 1.27)
					(thickness 0.15)
				)
				(justify left bottom)
				(hide yes)
			)
		)
		(property "Description" ""
			(at 116.84 148.59 0)
			(effects
				(font
					(size 1.27 1.27)
				)
				(hide yes)
			)
		)
		(property "MPN" "C1005X6S1A105K050BC"
			(at 134.62 128.27 0)
			(effects
				(font
					(size 1.27 1.27)
					(thickness 0.15)
				)
				(justify left bottom)
				(hide yes)
			)
		)
		(property "Manufacturer" "TDK"
			(at 137.16 128.27 0)
			(effects
				(font
					(size 1.27 1.27)
					(thickness 0.15)
				)
				(justify left bottom)
				(hide yes)
			)
		)
		(property "License" "Apache-2.0"
			(at 139.7 128.27 0)
			(effects
				(font
					(size 1.27 1.27)
					(thickness 0.15)
				)
				(justify left bottom)
				(hide yes)
			)
		)
		(property "Val" "1u"
			(at 117.475 147.955 90)
			(effects
				(font
					(size 1.27 1.27)
					(thickness 0.15)
				)
				(justify right)
			)
		)
		(property "Voltage" ""
			(at 144.78 128.27 0)
			(effects
				(font
					(size 1.27 1.27)
				)
				(justify left bottom)
				(hide yes)
			)
		)
		(property "Dielectric" ""
			(at 147.32 128.27 0)
			(effects
				(font
					(size 1.27 1.27)
				)
				(justify left bottom)
				(hide yes)
			)
		)
		(property "Author" "Antmicro"
			(at 142.24 128.27 0)
			(effects
				(font
					(size 1.27 1.27)
					(thickness 0.15)
				)
				(justify left bottom)
				(hide yes)
			)
		)
		(pin "1"
		)
		(pin "2"
		)
		(instances
			(project "thunderbolt-gpu-adapter"
				(path ""
					(reference "C67")
					(unit 1)
				)
			)
		)
	)
	(symbol
		(lib_id "antmicropower:GND")
		(at 105.41 203.2 0)
		(unit 1)
		(exclude_from_sim no)
		(in_bom yes)
		(on_board yes)
		(dnp no)
		(property "Reference" "#PWR082"
			(at 105.41 209.55 0)
			(effects
				(font
					(size 1.27 1.27)
				)
				(hide yes)
			)
		)
		(property "Value" "GND"
			(at 105.41 207.01 0)
			(effects
				(font
					(size 1.27 1.27)
				)
			)
		)
		(property "Footprint" ""
			(at 105.41 203.2 0)
			(effects
				(font
					(size 1.27 1.27)
				)
				(hide yes)
			)
		)
		(property "Datasheet" ""
			(at 105.41 203.2 0)
			(effects
				(font
					(size 1.27 1.27)
				)
				(hide yes)
			)
		)
		(property "Description" ""
			(at 105.41 203.2 0)
			(effects
				(font
					(size 1.27 1.27)
				)
				(hide yes)
			)
		)
		(property "Author" "Antmicro"
			(at 114.3 210.82 0)
			(effects
				(font
					(size 1.27 1.27)
					(thickness 0.15)
				)
				(justify left bottom)
				(hide yes)
			)
		)
		(property "License" "Apache-2.0"
			(at 114.3 213.36 0)
			(effects
				(font
					(size 1.27 1.27)
					(thickness 0.15)
				)
				(justify left bottom)
				(hide yes)
			)
		)
		(pin "1"
		)
		(instances
			(project "thunderbolt-gpu-adapter"
				(path ""
					(reference "#PWR082")
					(unit 1)
				)
			)
		)
	)
	(symbol
		(lib_id "antmicroCapacitors0402:C_1u_0402")
		(at 180.34 149.86 270)
		(mirror x)
		(unit 1)
		(exclude_from_sim no)
		(in_bom yes)
		(on_board yes)
		(dnp no)
		(fields_autoplaced yes)
		(property "Reference" "C73"
			(at 177.165 146.0436 90)
			(effects
				(font
					(size 1.27 1.27)
					(thickness 0.15)
				)
				(justify right)
			)
		)
		(property "Value" "C_1u_0402"
			(at 170.18 129.54 0)
			(effects
				(font
					(size 1.27 1.27)
					(thickness 0.15)
				)
				(justify left bottom)
				(hide yes)
			)
		)
		(property "Footprint" "antmicro-footprints:C_0402_1005Metric"
			(at 167.64 129.54 0)
			(effects
				(font
					(size 1.27 1.27)
					(thickness 0.15)
				)
				(justify left bottom)
				(hide yes)
			)
		)
		(property "Datasheet" "https://product.tdk.com/en/search/capacitor/ceramic/mlcc/info?part_no=C1005X6S1A105K050BC"
			(at 165.1 129.54 0)
			(effects
				(font
					(size 1.27 1.27)
					(thickness 0.15)
				)
				(justify left bottom)
				(hide yes)
			)
		)
		(property "Description" ""
			(at 180.34 149.86 0)
			(effects
				(font
					(size 1.27 1.27)
				)
				(hide yes)
			)
		)
		(property "MPN" "C1005X6S1A105K050BC"
			(at 162.56 129.54 0)
			(effects
				(font
					(size 1.27 1.27)
					(thickness 0.15)
				)
				(justify left bottom)
				(hide yes)
			)
		)
		(property "Manufacturer" "TDK"
			(at 160.02 129.54 0)
			(effects
				(font
					(size 1.27 1.27)
					(thickness 0.15)
				)
				(justify left bottom)
				(hide yes)
			)
		)
		(property "License" "Apache-2.0"
			(at 157.48 129.54 0)
			(effects
				(font
					(size 1.27 1.27)
					(thickness 0.15)
				)
				(justify left bottom)
				(hide yes)
			)
		)
		(property "Val" "1u"
			(at 177.165 148.5836 90)
			(effects
				(font
					(size 1.27 1.27)
					(thickness 0.15)
				)
				(justify right)
			)
		)
		(property "Voltage" ""
			(at 152.4 129.54 0)
			(effects
				(font
					(size 1.27 1.27)
				)
				(justify left bottom)
				(hide yes)
			)
		)
		(property "Dielectric" ""
			(at 149.86 129.54 0)
			(effects
				(font
					(size 1.27 1.27)
				)
				(justify left bottom)
				(hide yes)
			)
		)
		(property "Author" "Antmicro"
			(at 154.94 129.54 0)
			(effects
				(font
					(size 1.27 1.27)
					(thickness 0.15)
				)
				(justify left bottom)
				(hide yes)
			)
		)
		(pin "1"
		)
		(pin "2"
		)
		(instances
			(project "thunderbolt-gpu-adapter"
				(path ""
					(reference "C73")
					(unit 1)
				)
			)
		)
	)
	(symbol
		(lib_id "antmicropower:GND")
		(at 199.39 134.62 0)
		(unit 1)
		(exclude_from_sim no)
		(in_bom yes)
		(on_board yes)
		(dnp no)
		(property "Reference" "#PWR0123"
			(at 199.39 140.97 0)
			(effects
				(font
					(size 1.27 1.27)
				)
				(hide yes)
			)
		)
		(property "Value" "GND"
			(at 199.39 138.43 0)
			(effects
				(font
					(size 1.27 1.27)
				)
			)
		)
		(property "Footprint" ""
			(at 199.39 134.62 0)
			(effects
				(font
					(size 1.27 1.27)
				)
				(hide yes)
			)
		)
		(property "Datasheet" ""
			(at 199.39 134.62 0)
			(effects
				(font
					(size 1.27 1.27)
				)
				(hide yes)
			)
		)
		(property "Description" ""
			(at 199.39 134.62 0)
			(effects
				(font
					(size 1.27 1.27)
				)
				(hide yes)
			)
		)
		(property "Author" "Antmicro"
			(at 208.28 142.24 0)
			(effects
				(font
					(size 1.27 1.27)
					(thickness 0.15)
				)
				(justify left bottom)
				(hide yes)
			)
		)
		(property "License" "Apache-2.0"
			(at 208.28 144.78 0)
			(effects
				(font
					(size 1.27 1.27)
					(thickness 0.15)
				)
				(justify left bottom)
				(hide yes)
			)
		)
		(pin "1"
		)
		(instances
			(project "thunderbolt-gpu-adapter"
				(path ""
					(reference "#PWR0123")
					(unit 1)
				)
			)
		)
	)
	(symbol
		(lib_id "antmicropower:GND")
		(at 199.39 184.15 0)
		(unit 1)
		(exclude_from_sim no)
		(in_bom yes)
		(on_board yes)
		(dnp no)
		(property "Reference" "#PWR0112"
			(at 199.39 190.5 0)
			(effects
				(font
					(size 1.27 1.27)
				)
				(hide yes)
			)
		)
		(property "Value" "GND"
			(at 199.39 187.96 0)
			(effects
				(font
					(size 1.27 1.27)
				)
			)
		)
		(property "Footprint" ""
			(at 199.39 184.15 0)
			(effects
				(font
					(size 1.27 1.27)
				)
				(hide yes)
			)
		)
		(property "Datasheet" ""
			(at 199.39 184.15 0)
			(effects
				(font
					(size 1.27 1.27)
				)
				(hide yes)
			)
		)
		(property "Description" ""
			(at 199.39 184.15 0)
			(effects
				(font
					(size 1.27 1.27)
				)
				(hide yes)
			)
		)
		(property "Author" "Antmicro"
			(at 208.28 191.77 0)
			(effects
				(font
					(size 1.27 1.27)
					(thickness 0.15)
				)
				(justify left bottom)
				(hide yes)
			)
		)
		(property "License" "Apache-2.0"
			(at 208.28 194.31 0)
			(effects
				(font
					(size 1.27 1.27)
					(thickness 0.15)
				)
				(justify left bottom)
				(hide yes)
			)
		)
		(pin "1"
		)
		(instances
			(project "thunderbolt-gpu-adapter"
				(path ""
					(reference "#PWR0112")
					(unit 1)
				)
			)
		)
	)
	(symbol
		(lib_id "antmicroResistors0402:R_1k_0402")
		(at 199.39 281.94 0)
		(unit 1)
		(exclude_from_sim no)
		(in_bom yes)
		(on_board yes)
		(dnp no)
		(property "Reference" "R47"
			(at 201.93 280.035 0)
			(effects
				(font
					(size 1.27 1.27)
					(thickness 0.15)
				)
			)
		)
		(property "Value" "R_1k_0402"
			(at 219.71 294.64 0)
			(effects
				(font
					(size 1.27 1.27)
					(thickness 0.15)
				)
				(justify left bottom)
				(hide yes)
			)
		)
		(property "Footprint" "antmicro-footprints:R_0402_1005Metric"
			(at 219.71 297.18 0)
			(effects
				(font
					(size 1.27 1.27)
					(thickness 0.15)
				)
				(justify left bottom)
				(hide yes)
			)
		)
		(property "Datasheet" "https://www.bourns.com/docs/product-datasheets/cr.pdf"
			(at 219.71 299.72 0)
			(effects
				(font
					(size 1.27 1.27)
					(thickness 0.15)
				)
				(justify left bottom)
				(hide yes)
			)
		)
		(property "Description" ""
			(at 199.39 281.94 0)
			(effects
				(font
					(size 1.27 1.27)
				)
				(hide yes)
			)
		)
		(property "MPN" "CR0402-FX-1001GLF"
			(at 219.71 302.26 0)
			(effects
				(font
					(size 1.27 1.27)
					(thickness 0.15)
				)
				(justify left bottom)
				(hide yes)
			)
		)
		(property "Manufacturer" "Bourns"
			(at 219.71 304.8 0)
			(effects
				(font
					(size 1.27 1.27)
					(thickness 0.15)
				)
				(justify left bottom)
				(hide yes)
			)
		)
		(property "License" "Apache-2.0"
			(at 219.71 307.34 0)
			(effects
				(font
					(size 1.27 1.27)
					(thickness 0.15)
				)
				(justify left bottom)
				(hide yes)
			)
		)
		(property "Val" "1k"
			(at 201.93 283.845 0)
			(effects
				(font
					(size 1.27 1.27)
					(thickness 0.15)
				)
			)
		)
		(property "Tolerance" "1%"
			(at 219.71 292.1 0)
			(effects
				(font
					(size 1.27 1.27)
				)
				(justify left bottom)
				(hide yes)
			)
		)
		(property "Author" "Antmicro"
			(at 219.71 309.88 0)
			(effects
				(font
					(size 1.27 1.27)
					(thickness 0.15)
				)
				(justify left bottom)
				(hide yes)
			)
		)
		(pin "1"
		)
		(pin "2"
		)
		(instances
			(project "thunderbolt-gpu-adapter"
				(path ""
					(reference "R47")
					(unit 1)
				)
			)
		)
	)
	(symbol
		(lib_id "antmicroCapacitors0402:C_10u_0402")
		(at 218.44 133.35 90)
		(unit 1)
		(exclude_from_sim no)
		(in_bom yes)
		(on_board yes)
		(dnp no)
		(property "Reference" "C70"
			(at 219.075 128.905 90)
			(effects
				(font
					(size 1.27 1.27)
					(thickness 0.15)
				)
				(justify right)
			)
		)
		(property "Value" "C_10u_0402"
			(at 228.6 113.03 0)
			(effects
				(font
					(size 1.27 1.27)
					(thickness 0.15)
				)
				(justify left bottom)
				(hide yes)
			)
		)
		(property "Footprint" "antmicro-footprints:C_0402_1005Metric"
			(at 231.14 113.03 0)
			(effects
				(font
					(size 1.27 1.27)
					(thickness 0.15)
				)
				(justify left bottom)
				(hide yes)
			)
		)
		(property "Datasheet" "https://www.yageo.com/en/Chart/Download/pdf/CC0402MRX5R5BB106"
			(at 233.68 113.03 0)
			(effects
				(font
					(size 1.27 1.27)
					(thickness 0.15)
				)
				(justify left bottom)
				(hide yes)
			)
		)
		(property "Description" ""
			(at 218.44 133.35 0)
			(effects
				(font
					(size 1.27 1.27)
				)
				(hide yes)
			)
		)
		(property "MPN" "CC0402MRX5R5BB106"
			(at 236.22 113.03 0)
			(effects
				(font
					(size 1.27 1.27)
					(thickness 0.15)
				)
				(justify left bottom)
				(hide yes)
			)
		)
		(property "Manufacturer" "YAGEO"
			(at 238.76 113.03 0)
			(effects
				(font
					(size 1.27 1.27)
					(thickness 0.15)
				)
				(justify left bottom)
				(hide yes)
			)
		)
		(property "License" "Apache-2.0"
			(at 241.3 113.03 0)
			(effects
				(font
					(size 1.27 1.27)
					(thickness 0.15)
				)
				(justify left bottom)
				(hide yes)
			)
		)
		(property "Val" "10u"
			(at 219.075 132.715 90)
			(effects
				(font
					(size 1.27 1.27)
					(thickness 0.15)
				)
				(justify right)
			)
		)
		(property "Voltage" ""
			(at 246.38 113.03 0)
			(effects
				(font
					(size 1.27 1.27)
				)
				(justify left bottom)
				(hide yes)
			)
		)
		(property "Dielectric" ""
			(at 248.92 113.03 0)
			(effects
				(font
					(size 1.27 1.27)
				)
				(justify left bottom)
				(hide yes)
			)
		)
		(property "Author" "Antmicro"
			(at 243.84 113.03 0)
			(effects
				(font
					(size 1.27 1.27)
					(thickness 0.15)
				)
				(justify left bottom)
				(hide yes)
			)
		)
		(pin "1"
		)
		(pin "2"
		)
		(instances
			(project "thunderbolt-gpu-adapter"
				(path ""
					(reference "C70")
					(unit 1)
				)
			)
		)
	)
	(symbol
		(lib_id "antmicroCapacitors0402:C_1u_0402")
		(at 116.84 184.15 90)
		(unit 1)
		(exclude_from_sim no)
		(in_bom yes)
		(on_board yes)
		(dnp no)
		(fields_autoplaced yes)
		(property "Reference" "C52"
			(at 119.38 180.3336 90)
			(effects
				(font
					(size 1.27 1.27)
					(thickness 0.15)
				)
				(justify right)
			)
		)
		(property "Value" "C_1u_0402"
			(at 127 163.83 0)
			(effects
				(font
					(size 1.27 1.27)
					(thickness 0.15)
				)
				(justify left bottom)
				(hide yes)
			)
		)
		(property "Footprint" "antmicro-footprints:C_0402_1005Metric"
			(at 129.54 163.83 0)
			(effects
				(font
					(size 1.27 1.27)
					(thickness 0.15)
				)
				(justify left bottom)
				(hide yes)
			)
		)
		(property "Datasheet" "https://product.tdk.com/en/search/capacitor/ceramic/mlcc/info?part_no=C1005X6S1A105K050BC"
			(at 132.08 163.83 0)
			(effects
				(font
					(size 1.27 1.27)
					(thickness 0.15)
				)
				(justify left bottom)
				(hide yes)
			)
		)
		(property "Description" ""
			(at 116.84 184.15 0)
			(effects
				(font
					(size 1.27 1.27)
				)
				(hide yes)
			)
		)
		(property "MPN" "C1005X6S1A105K050BC"
			(at 134.62 163.83 0)
			(effects
				(font
					(size 1.27 1.27)
					(thickness 0.15)
				)
				(justify left bottom)
				(hide yes)
			)
		)
		(property "Manufacturer" "TDK"
			(at 137.16 163.83 0)
			(effects
				(font
					(size 1.27 1.27)
					(thickness 0.15)
				)
				(justify left bottom)
				(hide yes)
			)
		)
		(property "License" "Apache-2.0"
			(at 139.7 163.83 0)
			(effects
				(font
					(size 1.27 1.27)
					(thickness 0.15)
				)
				(justify left bottom)
				(hide yes)
			)
		)
		(property "Val" "1u"
			(at 119.38 182.8736 90)
			(effects
				(font
					(size 1.27 1.27)
					(thickness 0.15)
				)
				(justify right)
			)
		)
		(property "Voltage" ""
			(at 144.78 163.83 0)
			(effects
				(font
					(size 1.27 1.27)
				)
				(justify left bottom)
				(hide yes)
			)
		)
		(property "Dielectric" ""
			(at 147.32 163.83 0)
			(effects
				(font
					(size 1.27 1.27)
				)
				(justify left bottom)
				(hide yes)
			)
		)
		(property "Author" "Antmicro"
			(at 142.24 163.83 0)
			(effects
				(font
					(size 1.27 1.27)
					(thickness 0.15)
				)
				(justify left bottom)
				(hide yes)
			)
		)
		(pin "1"
		)
		(pin "2"
		)
		(instances
			(project "thunderbolt-gpu-adapter"
				(path ""
					(reference "C52")
					(unit 1)
				)
			)
		)
	)
	(symbol
		(lib_id "antmicroCapacitors0402:C_1u_0402")
		(at 105.41 166.37 90)
		(unit 1)
		(exclude_from_sim no)
		(in_bom yes)
		(on_board yes)
		(dnp no)
		(property "Reference" "C62"
			(at 106.045 161.925 90)
			(effects
				(font
					(size 1.27 1.27)
					(thickness 0.15)
				)
				(justify right)
			)
		)
		(property "Value" "C_1u_0402"
			(at 115.57 146.05 0)
			(effects
				(font
					(size 1.27 1.27)
					(thickness 0.15)
				)
				(justify left bottom)
				(hide yes)
			)
		)
		(property "Footprint" "antmicro-footprints:C_0402_1005Metric"
			(at 118.11 146.05 0)
			(effects
				(font
					(size 1.27 1.27)
					(thickness 0.15)
				)
				(justify left bottom)
				(hide yes)
			)
		)
		(property "Datasheet" "https://product.tdk.com/en/search/capacitor/ceramic/mlcc/info?part_no=C1005X6S1A105K050BC"
			(at 120.65 146.05 0)
			(effects
				(font
					(size 1.27 1.27)
					(thickness 0.15)
				)
				(justify left bottom)
				(hide yes)
			)
		)
		(property "Description" ""
			(at 105.41 166.37 0)
			(effects
				(font
					(size 1.27 1.27)
				)
				(hide yes)
			)
		)
		(property "MPN" "C1005X6S1A105K050BC"
			(at 123.19 146.05 0)
			(effects
				(font
					(size 1.27 1.27)
					(thickness 0.15)
				)
				(justify left bottom)
				(hide yes)
			)
		)
		(property "Manufacturer" "TDK"
			(at 125.73 146.05 0)
			(effects
				(font
					(size 1.27 1.27)
					(thickness 0.15)
				)
				(justify left bottom)
				(hide yes)
			)
		)
		(property "License" "Apache-2.0"
			(at 128.27 146.05 0)
			(effects
				(font
					(size 1.27 1.27)
					(thickness 0.15)
				)
				(justify left bottom)
				(hide yes)
			)
		)
		(property "Val" "1u"
			(at 106.045 165.735 90)
			(effects
				(font
					(size 1.27 1.27)
					(thickness 0.15)
				)
				(justify right)
			)
		)
		(property "Voltage" ""
			(at 133.35 146.05 0)
			(effects
				(font
					(size 1.27 1.27)
				)
				(justify left bottom)
				(hide yes)
			)
		)
		(property "Dielectric" ""
			(at 135.89 146.05 0)
			(effects
				(font
					(size 1.27 1.27)
				)
				(justify left bottom)
				(hide yes)
			)
		)
		(property "Author" "Antmicro"
			(at 130.81 146.05 0)
			(effects
				(font
					(size 1.27 1.27)
					(thickness 0.15)
				)
				(justify left bottom)
				(hide yes)
			)
		)
		(pin "1"
		)
		(pin "2"
		)
		(instances
			(project "thunderbolt-gpu-adapter"
				(path ""
					(reference "C62")
					(unit 1)
				)
			)
		)
	)
	(symbol
		(lib_id "antmicropower:GND")
		(at 116.84 224.79 0)
		(unit 1)
		(exclude_from_sim no)
		(in_bom yes)
		(on_board yes)
		(dnp no)
		(property "Reference" "#PWR094"
			(at 116.84 231.14 0)
			(effects
				(font
					(size 1.27 1.27)
				)
				(hide yes)
			)
		)
		(property "Value" "GND"
			(at 116.84 228.6 0)
			(effects
				(font
					(size 1.27 1.27)
				)
			)
		)
		(property "Footprint" ""
			(at 116.84 224.79 0)
			(effects
				(font
					(size 1.27 1.27)
				)
				(hide yes)
			)
		)
		(property "Datasheet" ""
			(at 116.84 224.79 0)
			(effects
				(font
					(size 1.27 1.27)
				)
				(hide yes)
			)
		)
		(property "Description" ""
			(at 116.84 224.79 0)
			(effects
				(font
					(size 1.27 1.27)
				)
				(hide yes)
			)
		)
		(property "Author" "Antmicro"
			(at 125.73 232.41 0)
			(effects
				(font
					(size 1.27 1.27)
					(thickness 0.15)
				)
				(justify left bottom)
				(hide yes)
			)
		)
		(property "License" "Apache-2.0"
			(at 125.73 234.95 0)
			(effects
				(font
					(size 1.27 1.27)
					(thickness 0.15)
				)
				(justify left bottom)
				(hide yes)
			)
		)
		(pin "1"
		)
		(instances
			(project "thunderbolt-gpu-adapter"
				(path ""
					(reference "#PWR094")
					(unit 1)
				)
			)
		)
	)
	(symbol
		(lib_id "antmicroCapacitors0402:C_1u_0402")
		(at 100.33 201.93 90)
		(unit 1)
		(exclude_from_sim no)
		(in_bom yes)
		(on_board yes)
		(dnp no)
		(property "Reference" "C54"
			(at 100.965 197.485 90)
			(effects
				(font
					(size 1.27 1.27)
					(thickness 0.15)
				)
				(justify right)
			)
		)
		(property "Value" "C_1u_0402"
			(at 110.49 181.61 0)
			(effects
				(font
					(size 1.27 1.27)
					(thickness 0.15)
				)
				(justify left bottom)
				(hide yes)
			)
		)
		(property "Footprint" "antmicro-footprints:C_0402_1005Metric"
			(at 113.03 181.61 0)
			(effects
				(font
					(size 1.27 1.27)
					(thickness 0.15)
				)
				(justify left bottom)
				(hide yes)
			)
		)
		(property "Datasheet" "https://product.tdk.com/en/search/capacitor/ceramic/mlcc/info?part_no=C1005X6S1A105K050BC"
			(at 115.57 181.61 0)
			(effects
				(font
					(size 1.27 1.27)
					(thickness 0.15)
				)
				(justify left bottom)
				(hide yes)
			)
		)
		(property "Description" ""
			(at 100.33 201.93 0)
			(effects
				(font
					(size 1.27 1.27)
				)
				(hide yes)
			)
		)
		(property "MPN" "C1005X6S1A105K050BC"
			(at 118.11 181.61 0)
			(effects
				(font
					(size 1.27 1.27)
					(thickness 0.15)
				)
				(justify left bottom)
				(hide yes)
			)
		)
		(property "Manufacturer" "TDK"
			(at 120.65 181.61 0)
			(effects
				(font
					(size 1.27 1.27)
					(thickness 0.15)
				)
				(justify left bottom)
				(hide yes)
			)
		)
		(property "License" "Apache-2.0"
			(at 123.19 181.61 0)
			(effects
				(font
					(size 1.27 1.27)
					(thickness 0.15)
				)
				(justify left bottom)
				(hide yes)
			)
		)
		(property "Val" "1u"
			(at 100.965 201.295 90)
			(effects
				(font
					(size 1.27 1.27)
					(thickness 0.15)
				)
				(justify right)
			)
		)
		(property "Voltage" ""
			(at 128.27 181.61 0)
			(effects
				(font
					(size 1.27 1.27)
				)
				(justify left bottom)
				(hide yes)
			)
		)
		(property "Dielectric" ""
			(at 130.81 181.61 0)
			(effects
				(font
					(size 1.27 1.27)
				)
				(justify left bottom)
				(hide yes)
			)
		)
		(property "Author" "Antmicro"
			(at 125.73 181.61 0)
			(effects
				(font
					(size 1.27 1.27)
					(thickness 0.15)
				)
				(justify left bottom)
				(hide yes)
			)
		)
		(pin "1"
		)
		(pin "2"
		)
		(instances
			(project "thunderbolt-gpu-adapter"
				(path ""
					(reference "C54")
					(unit 1)
				)
			)
		)
	)
	(symbol
		(lib_id "antmicroCapacitors0402:C_1u_0402")
		(at 205.74 182.88 90)
		(unit 1)
		(exclude_from_sim no)
		(in_bom yes)
		(on_board yes)
		(dnp no)
		(property "Reference" "C87"
			(at 206.375 178.435 90)
			(effects
				(font
					(size 1.27 1.27)
					(thickness 0.15)
				)
				(justify right)
			)
		)
		(property "Value" "C_1u_0402"
			(at 215.9 162.56 0)
			(effects
				(font
					(size 1.27 1.27)
					(thickness 0.15)
				)
				(justify left bottom)
				(hide yes)
			)
		)
		(property "Footprint" "antmicro-footprints:C_0402_1005Metric"
			(at 218.44 162.56 0)
			(effects
				(font
					(size 1.27 1.27)
					(thickness 0.15)
				)
				(justify left bottom)
				(hide yes)
			)
		)
		(property "Datasheet" "https://product.tdk.com/en/search/capacitor/ceramic/mlcc/info?part_no=C1005X6S1A105K050BC"
			(at 220.98 162.56 0)
			(effects
				(font
					(size 1.27 1.27)
					(thickness 0.15)
				)
				(justify left bottom)
				(hide yes)
			)
		)
		(property "Description" ""
			(at 205.74 182.88 0)
			(effects
				(font
					(size 1.27 1.27)
				)
				(hide yes)
			)
		)
		(property "MPN" "C1005X6S1A105K050BC"
			(at 223.52 162.56 0)
			(effects
				(font
					(size 1.27 1.27)
					(thickness 0.15)
				)
				(justify left bottom)
				(hide yes)
			)
		)
		(property "Manufacturer" "TDK"
			(at 226.06 162.56 0)
			(effects
				(font
					(size 1.27 1.27)
					(thickness 0.15)
				)
				(justify left bottom)
				(hide yes)
			)
		)
		(property "License" "Apache-2.0"
			(at 228.6 162.56 0)
			(effects
				(font
					(size 1.27 1.27)
					(thickness 0.15)
				)
				(justify left bottom)
				(hide yes)
			)
		)
		(property "Val" "1u"
			(at 206.375 182.245 90)
			(effects
				(font
					(size 1.27 1.27)
					(thickness 0.15)
				)
				(justify right)
			)
		)
		(property "Voltage" ""
			(at 233.68 162.56 0)
			(effects
				(font
					(size 1.27 1.27)
				)
				(justify left bottom)
				(hide yes)
			)
		)
		(property "Dielectric" ""
			(at 236.22 162.56 0)
			(effects
				(font
					(size 1.27 1.27)
				)
				(justify left bottom)
				(hide yes)
			)
		)
		(property "Author" "Antmicro"
			(at 231.14 162.56 0)
			(effects
				(font
					(size 1.27 1.27)
					(thickness 0.15)
				)
				(justify left bottom)
				(hide yes)
			)
		)
		(pin "1"
		)
		(pin "2"
		)
		(instances
			(project "thunderbolt-gpu-adapter"
				(path ""
					(reference "C87")
					(unit 1)
				)
			)
		)
	)
	(symbol
		(lib_id "antmicroTestPoints:TP_1mm_SMD")
		(at 219.71 191.77 90)
		(unit 1)
		(exclude_from_sim no)
		(in_bom no)
		(on_board yes)
		(dnp no)
		(fields_autoplaced yes)
		(property "Reference" "TP9"
			(at 222.25 188.595 90)
			(effects
				(font
					(size 1.27 1.27)
					(thickness 0.15)
				)
				(justify right)
			)
		)
		(property "Value" "TP_1mm_SMD"
			(at 221.615 188.5949 90)
			(effects
				(font
					(size 1.27 1.27)
					(thickness 0.15)
				)
				(justify right)
				(hide yes)
			)
		)
		(property "Footprint" "antmicro-footprints:TP_SMD_1mm"
			(at 229.87 176.53 0)
			(effects
				(font
					(size 1.27 1.27)
					(thickness 0.15)
				)
				(justify left bottom)
				(hide yes)
			)
		)
		(property "Datasheet" ""
			(at 232.41 176.53 0)
			(effects
				(font
					(size 1.27 1.27)
					(thickness 0.15)
				)
				(justify left bottom)
				(hide yes)
			)
		)
		(property "Description" ""
			(at 219.71 191.77 0)
			(effects
				(font
					(size 1.27 1.27)
				)
				(hide yes)
			)
		)
		(property "License" "Apache-2.0"
			(at 237.49 176.53 0)
			(effects
				(font
					(size 1.27 1.27)
					(thickness 0.15)
				)
				(justify left bottom)
				(hide yes)
			)
		)
		(property "Manufacturer" ""
			(at 221.615 191.1349 90)
			(effects
				(font
					(size 1.27 1.27)
				)
				(justify right)
				(hide yes)
			)
		)
		(property "MPN" ""
			(at 219.71 191.77 0)
			(effects
				(font
					(size 1.27 1.27)
				)
				(hide yes)
			)
		)
		(property "Author" "Antmicro"
			(at 234.95 176.53 0)
			(effects
				(font
					(size 1.27 1.27)
					(thickness 0.15)
				)
				(justify left bottom)
				(hide yes)
			)
		)
		(pin "1"
		)
		(instances
			(project "thunderbolt-gpu-adapter"
				(path ""
					(reference "TP9")
					(unit 1)
				)
			)
		)
	)
	(symbol
		(lib_id "antmicropower:GND")
		(at 116.84 151.13 0)
		(unit 1)
		(exclude_from_sim no)
		(in_bom yes)
		(on_board yes)
		(dnp no)
		(property "Reference" "#PWR092"
			(at 116.84 157.48 0)
			(effects
				(font
					(size 1.27 1.27)
				)
				(hide yes)
			)
		)
		(property "Value" "GND"
			(at 116.84 154.94 0)
			(effects
				(font
					(size 1.27 1.27)
				)
			)
		)
		(property "Footprint" ""
			(at 116.84 151.13 0)
			(effects
				(font
					(size 1.27 1.27)
				)
				(hide yes)
			)
		)
		(property "Datasheet" ""
			(at 116.84 151.13 0)
			(effects
				(font
					(size 1.27 1.27)
				)
				(hide yes)
			)
		)
		(property "Description" ""
			(at 116.84 151.13 0)
			(effects
				(font
					(size 1.27 1.27)
				)
				(hide yes)
			)
		)
		(property "Author" "Antmicro"
			(at 125.73 158.75 0)
			(effects
				(font
					(size 1.27 1.27)
					(thickness 0.15)
				)
				(justify left bottom)
				(hide yes)
			)
		)
		(property "License" "Apache-2.0"
			(at 125.73 161.29 0)
			(effects
				(font
					(size 1.27 1.27)
					(thickness 0.15)
				)
				(justify left bottom)
				(hide yes)
			)
		)
		(pin "1"
		)
		(instances
			(project "thunderbolt-gpu-adapter"
				(path ""
					(reference "#PWR092")
					(unit 1)
				)
			)
		)
	)
	(symbol
		(lib_id "antmicroCapacitors0603:C_22u_0603")
		(at 199.39 201.93 90)
		(unit 1)
		(exclude_from_sim no)
		(in_bom yes)
		(on_board yes)
		(dnp no)
		(property "Reference" "C86"
			(at 200.025 197.485 90)
			(effects
				(font
					(size 1.27 1.27)
					(thickness 0.15)
				)
				(justify right)
			)
		)
		(property "Value" "C_22u_0603"
			(at 209.55 181.61 0)
			(effects
				(font
					(size 1.27 1.27)
					(thickness 0.15)
				)
				(justify left bottom)
				(hide yes)
			)
		)
		(property "Footprint" "antmicro-footprints:C_0603_1608Metric"
			(at 212.09 181.61 0)
			(effects
				(font
					(size 1.27 1.27)
					(thickness 0.15)
				)
				(justify left bottom)
				(hide yes)
			)
		)
		(property "Datasheet" "https://www.murata.com/products/productdetail?partno=GRM188R60J226MEA0%23"
			(at 214.63 181.61 0)
			(effects
				(font
					(size 1.27 1.27)
					(thickness 0.15)
				)
				(justify left bottom)
				(hide yes)
			)
		)
		(property "Description" ""
			(at 199.39 201.93 0)
			(effects
				(font
					(size 1.27 1.27)
				)
				(hide yes)
			)
		)
		(property "MPN" "GRM188R60J226MEA0D"
			(at 217.17 181.61 0)
			(effects
				(font
					(size 1.27 1.27)
					(thickness 0.15)
				)
				(justify left bottom)
				(hide yes)
			)
		)
		(property "Manufacturer" "Murata"
			(at 219.71 181.61 0)
			(effects
				(font
					(size 1.27 1.27)
					(thickness 0.15)
				)
				(justify left bottom)
				(hide yes)
			)
		)
		(property "License" "Apache-2.0"
			(at 222.25 181.61 0)
			(effects
				(font
					(size 1.27 1.27)
					(thickness 0.15)
				)
				(justify left bottom)
				(hide yes)
			)
		)
		(property "Val" "22u"
			(at 200.025 201.295 90)
			(effects
				(font
					(size 1.27 1.27)
					(thickness 0.15)
				)
				(justify right)
			)
		)
		(property "Voltage" ""
			(at 227.33 181.61 0)
			(effects
				(font
					(size 1.27 1.27)
				)
				(justify left bottom)
				(hide yes)
			)
		)
		(property "Dielectric" ""
			(at 229.87 181.61 0)
			(effects
				(font
					(size 1.27 1.27)
				)
				(justify left bottom)
				(hide yes)
			)
		)
		(property "Author" "Antmicro"
			(at 224.79 181.61 0)
			(effects
				(font
					(size 1.27 1.27)
					(thickness 0.15)
				)
				(justify left bottom)
				(hide yes)
			)
		)
		(pin "1"
		)
		(pin "2"
		)
		(instances
			(project "thunderbolt-gpu-adapter"
				(path ""
					(reference "C86")
					(unit 1)
				)
			)
		)
	)
	(symbol
		(lib_id "antmicroResistors0402:R_8k2_0402")
		(at 217.17 214.63 90)
		(unit 1)
		(exclude_from_sim no)
		(in_bom yes)
		(on_board yes)
		(dnp no)
		(fields_autoplaced yes)
		(property "Reference" "R145"
			(at 219.71 210.82 90)
			(effects
				(font
					(size 1.27 1.27)
					(thickness 0.15)
				)
				(justify right)
			)
		)
		(property "Value" "R_8k2_0402"
			(at 229.87 194.31 0)
			(effects
				(font
					(size 1.27 1.27)
					(thickness 0.15)
				)
				(justify left bottom)
				(hide yes)
			)
		)
		(property "Footprint" "antmicro-footprints:R_0402_1005Metric"
			(at 232.41 194.31 0)
			(effects
				(font
					(size 1.27 1.27)
					(thickness 0.15)
				)
				(justify left bottom)
				(hide yes)
			)
		)
		(property "Datasheet" "https://www.bourns.com/docs/product-datasheets/cr.pdf"
			(at 234.95 194.31 0)
			(effects
				(font
					(size 1.27 1.27)
					(thickness 0.15)
				)
				(justify left bottom)
				(hide yes)
			)
		)
		(property "Description" ""
			(at 217.17 214.63 0)
			(effects
				(font
					(size 1.27 1.27)
				)
				(hide yes)
			)
		)
		(property "MPN" "CR0402-FX-8201GLF"
			(at 237.49 194.31 0)
			(effects
				(font
					(size 1.27 1.27)
					(thickness 0.15)
				)
				(justify left bottom)
				(hide yes)
			)
		)
		(property "Manufacturer" "Bourns"
			(at 240.03 194.31 0)
			(effects
				(font
					(size 1.27 1.27)
					(thickness 0.15)
				)
				(justify left bottom)
				(hide yes)
			)
		)
		(property "License" "Apache-2.0"
			(at 242.57 194.31 0)
			(effects
				(font
					(size 1.27 1.27)
					(thickness 0.15)
				)
				(justify left bottom)
				(hide yes)
			)
		)
		(property "Author" "Antmicro"
			(at 245.11 194.31 0)
			(effects
				(font
					(size 1.27 1.27)
					(thickness 0.15)
				)
				(justify left bottom)
				(hide yes)
			)
		)
		(property "Val" "8k2"
			(at 219.71 213.36 90)
			(effects
				(font
					(size 1.27 1.27)
					(thickness 0.15)
				)
				(justify right)
			)
		)
		(property "Tolerance" "1%"
			(at 227.33 194.31 0)
			(effects
				(font
					(size 1.27 1.27)
				)
				(justify left bottom)
				(hide yes)
			)
		)
		(pin "1"
		)
		(pin "2"
		)
		(instances
			(project "thunderbolt-gpu-adapter"
				(path ""
					(reference "R145")
					(unit 1)
				)
			)
		)
	)
	(symbol
		(lib_id "antmicroCapacitors0603:C_22u_0603")
		(at 193.04 201.93 90)
		(unit 1)
		(exclude_from_sim no)
		(in_bom yes)
		(on_board yes)
		(dnp no)
		(property "Reference" "C82"
			(at 193.675 197.485 90)
			(effects
				(font
					(size 1.27 1.27)
					(thickness 0.15)
				)
				(justify right)
			)
		)
		(property "Value" "C_22u_0603"
			(at 203.2 181.61 0)
			(effects
				(font
					(size 1.27 1.27)
					(thickness 0.15)
				)
				(justify left bottom)
				(hide yes)
			)
		)
		(property "Footprint" "antmicro-footprints:C_0603_1608Metric"
			(at 205.74 181.61 0)
			(effects
				(font
					(size 1.27 1.27)
					(thickness 0.15)
				)
				(justify left bottom)
				(hide yes)
			)
		)
		(property "Datasheet" "https://www.murata.com/products/productdetail?partno=GRM188R60J226MEA0%23"
			(at 208.28 181.61 0)
			(effects
				(font
					(size 1.27 1.27)
					(thickness 0.15)
				)
				(justify left bottom)
				(hide yes)
			)
		)
		(property "Description" ""
			(at 193.04 201.93 0)
			(effects
				(font
					(size 1.27 1.27)
				)
				(hide yes)
			)
		)
		(property "MPN" "GRM188R60J226MEA0D"
			(at 210.82 181.61 0)
			(effects
				(font
					(size 1.27 1.27)
					(thickness 0.15)
				)
				(justify left bottom)
				(hide yes)
			)
		)
		(property "Manufacturer" "Murata"
			(at 213.36 181.61 0)
			(effects
				(font
					(size 1.27 1.27)
					(thickness 0.15)
				)
				(justify left bottom)
				(hide yes)
			)
		)
		(property "License" "Apache-2.0"
			(at 215.9 181.61 0)
			(effects
				(font
					(size 1.27 1.27)
					(thickness 0.15)
				)
				(justify left bottom)
				(hide yes)
			)
		)
		(property "Val" "22u"
			(at 193.675 201.295 90)
			(effects
				(font
					(size 1.27 1.27)
					(thickness 0.15)
				)
				(justify right)
			)
		)
		(property "Voltage" ""
			(at 220.98 181.61 0)
			(effects
				(font
					(size 1.27 1.27)
				)
				(justify left bottom)
				(hide yes)
			)
		)
		(property "Dielectric" ""
			(at 223.52 181.61 0)
			(effects
				(font
					(size 1.27 1.27)
				)
				(justify left bottom)
				(hide yes)
			)
		)
		(property "Author" "Antmicro"
			(at 218.44 181.61 0)
			(effects
				(font
					(size 1.27 1.27)
					(thickness 0.15)
				)
				(justify left bottom)
				(hide yes)
			)
		)
		(pin "1"
		)
		(pin "2"
		)
		(instances
			(project "thunderbolt-gpu-adapter"
				(path ""
					(reference "C82")
					(unit 1)
				)
			)
		)
	)
	(symbol
		(lib_id "antmicropower:GND")
		(at 186.69 203.2 0)
		(unit 1)
		(exclude_from_sim no)
		(in_bom yes)
		(on_board yes)
		(dnp no)
		(property "Reference" "#PWR0107"
			(at 186.69 209.55 0)
			(effects
				(font
					(size 1.27 1.27)
				)
				(hide yes)
			)
		)
		(property "Value" "GND"
			(at 186.69 207.01 0)
			(effects
				(font
					(size 1.27 1.27)
				)
			)
		)
		(property "Footprint" ""
			(at 186.69 203.2 0)
			(effects
				(font
					(size 1.27 1.27)
				)
				(hide yes)
			)
		)
		(property "Datasheet" ""
			(at 186.69 203.2 0)
			(effects
				(font
					(size 1.27 1.27)
				)
				(hide yes)
			)
		)
		(property "Description" ""
			(at 186.69 203.2 0)
			(effects
				(font
					(size 1.27 1.27)
				)
				(hide yes)
			)
		)
		(property "Author" "Antmicro"
			(at 195.58 210.82 0)
			(effects
				(font
					(size 1.27 1.27)
					(thickness 0.15)
				)
				(justify left bottom)
				(hide yes)
			)
		)
		(property "License" "Apache-2.0"
			(at 195.58 213.36 0)
			(effects
				(font
					(size 1.27 1.27)
					(thickness 0.15)
				)
				(justify left bottom)
				(hide yes)
			)
		)
		(pin "1"
		)
		(instances
			(project "thunderbolt-gpu-adapter"
				(path ""
					(reference "#PWR0107")
					(unit 1)
				)
			)
		)
	)
	(symbol
		(lib_id "antmicropower:GND")
		(at 212.09 134.62 0)
		(unit 1)
		(exclude_from_sim no)
		(in_bom yes)
		(on_board yes)
		(dnp no)
		(property "Reference" "#PWR0221"
			(at 212.09 140.97 0)
			(effects
				(font
					(size 1.27 1.27)
				)
				(hide yes)
			)
		)
		(property "Value" "GND"
			(at 212.09 138.43 0)
			(effects
				(font
					(size 1.27 1.27)
				)
			)
		)
		(property "Footprint" ""
			(at 212.09 134.62 0)
			(effects
				(font
					(size 1.27 1.27)
				)
				(hide yes)
			)
		)
		(property "Datasheet" ""
			(at 212.09 134.62 0)
			(effects
				(font
					(size 1.27 1.27)
				)
				(hide yes)
			)
		)
		(property "Description" ""
			(at 212.09 134.62 0)
			(effects
				(font
					(size 1.27 1.27)
				)
				(hide yes)
			)
		)
		(property "Author" "Antmicro"
			(at 220.98 142.24 0)
			(effects
				(font
					(size 1.27 1.27)
					(thickness 0.15)
				)
				(justify left bottom)
				(hide yes)
			)
		)
		(property "License" "Apache-2.0"
			(at 220.98 144.78 0)
			(effects
				(font
					(size 1.27 1.27)
					(thickness 0.15)
				)
				(justify left bottom)
				(hide yes)
			)
		)
		(pin "1"
		)
		(instances
			(project "thunderbolt-gpu-adapter"
				(path ""
					(reference "#PWR0221")
					(unit 1)
				)
			)
		)
	)
	(symbol
		(lib_id "antmicropower:GND")
		(at 186.69 167.64 0)
		(unit 1)
		(exclude_from_sim no)
		(in_bom yes)
		(on_board yes)
		(dnp no)
		(property "Reference" "#PWR0120"
			(at 186.69 173.99 0)
			(effects
				(font
					(size 1.27 1.27)
				)
				(hide yes)
			)
		)
		(property "Value" "GND"
			(at 186.69 171.45 0)
			(effects
				(font
					(size 1.27 1.27)
				)
			)
		)
		(property "Footprint" ""
			(at 186.69 167.64 0)
			(effects
				(font
					(size 1.27 1.27)
				)
				(hide yes)
			)
		)
		(property "Datasheet" ""
			(at 186.69 167.64 0)
			(effects
				(font
					(size 1.27 1.27)
				)
				(hide yes)
			)
		)
		(property "Description" ""
			(at 186.69 167.64 0)
			(effects
				(font
					(size 1.27 1.27)
				)
				(hide yes)
			)
		)
		(property "Author" "Antmicro"
			(at 195.58 175.26 0)
			(effects
				(font
					(size 1.27 1.27)
					(thickness 0.15)
				)
				(justify left bottom)
				(hide yes)
			)
		)
		(property "License" "Apache-2.0"
			(at 195.58 177.8 0)
			(effects
				(font
					(size 1.27 1.27)
					(thickness 0.15)
				)
				(justify left bottom)
				(hide yes)
			)
		)
		(pin "1"
		)
		(instances
			(project "thunderbolt-gpu-adapter"
				(path ""
					(reference "#PWR0120")
					(unit 1)
				)
			)
		)
	)
)
